G04 ================== begin FILE IDENTIFICATION RECORD ==================*
G04 Layout Name:  12432-1.brd*
G04 Film Name:    L2GND*
G04 File Format:  Gerber RS274X*
G04 File Origin:  Cadence Allegro 16.2-S037*
G04 Origin Date:  Wed Oct 17 11:00:01 2012*
G04 *
G04 Layer:  VIA CLASS/L2GND*
G04 Layer:  PIN/L2GND*
G04 Layer:  ETCH/L2GND*
G04 Layer:  DRAWING FORMAT/LAYER_PCB_STORY*
G04 Layer:  DRAWING FORMAT/LAYER_L2GND*
G04 *
G04 Offset:    (0.00 0.00)*
G04 Mirror:    No*
G04 Mode:      Negative*
G04 Rotation:  0*
G04 FullContactRelief:  No*
G04 UndefLineWidth:     6.00*
G04 ================== end FILE IDENTIFICATION RECORD ====================*
%FSLAX35Y35*MOIN*%
%IR0*IPPOS*OFA0.00000B0.00000*MIA0B0*SFA1.00000B1.00000*%
%AMMACRO19*
4,1,16,.07873,.05044,
.086293,.036002,
.091233,.020471,
.093402,.004317,
.092733,-.011967,
.089246,-.027888,
.083047,-.042962,
.07873,-.05044,
.08234,-.05406,
.090476,-.038941,
.095864,-.022638,
.098339,-.005647,
.097825,.011515,
.094339,.028327,
.087987,.044279,
.08234,.05406,
.07873,.05044,
0.0*
4,1,16,.05044,-.07873,
.036002,-.086293,
.020471,-.091233,
.004317,-.093402,
-.011967,-.092733,
-.027888,-.089246,
-.042962,-.083047,
-.05044,-.07873,
-.05406,-.08234,
-.038941,-.090476,
-.022638,-.095864,
-.005647,-.098339,
.011515,-.097825,
.028327,-.094339,
.044279,-.087987,
.05406,-.08234,
.05044,-.07873,
0.0*
4,1,16,-.07873,-.05044,
-.086293,-.036002,
-.091233,-.020471,
-.093402,-.004317,
-.092733,.011967,
-.089246,.027888,
-.083047,.042962,
-.07873,.05044,
-.08234,.05406,
-.090476,.038941,
-.095864,.022638,
-.098339,.005647,
-.097825,-.011515,
-.094339,-.028327,
-.087987,-.044279,
-.08234,-.05406,
-.07873,-.05044,
0.0*
4,1,16,-.05044,.07873,
-.036002,.086293,
-.020471,.091233,
-.004317,.093402,
.011967,.092733,
.027888,.089246,
.042962,.083047,
.05044,.07873,
.05406,.08234,
.038941,.090476,
.022638,.095864,
.005647,.098339,
-.011515,.097825,
-.028327,.094339,
-.044279,.087987,
-.05406,.08234,
-.05044,.07873,
0.0*
%
%ADD19MACRO19*%
%ADD15C,.032*%
%AMMACRO21*
4,1,20,-.01,-.05608,
-.015853,-.053819,
-.021224,-.050576,
-.025951,-.046449,
-.029889,-.041565,
-.032919,-.03607,
-.034949,-.030133,
-.035918,-.023934,
-.036,-.0215,
-.036,-.015,
-.031,-.015,
-.031,-.0215,
-.030529,-.026882,
-.029131,-.032101,
-.026847,-.036998,
-.023748,-.041424,
-.019928,-.045244,
-.015502,-.048343,
-.010605,-.050627,
-.01,-.05084,
-.01,-.05608,
90.*
4,1,20,.01,-.05608,
.01,-.05084,
.014943,-.048658,
.019432,-.045652,
.023331,-.041911,
.026521,-.03755,
.028905,-.032702,
.030411,-.027513,
.030993,-.022142,
.031,-.0215,
.031,-.015,
.036,-.015,
.036,-.0215,
.035453,-.027751,
.033829,-.033811,
.031177,-.039498,
.027579,-.044638,
.023142,-.049074,
.018002,-.052673,
.012316,-.055325,
.01,-.05608,
90.*
4,1,20,-.036,.015,
-.036,.0215,
-.035453,.027751,
-.033829,.033811,
-.031177,.039498,
-.027579,.044638,
-.023142,.049074,
-.018002,.052673,
-.012316,.055325,
-.01,.05608,
-.01,.05084,
-.014943,.048658,
-.019432,.045652,
-.023331,.041911,
-.026521,.03755,
-.028905,.032702,
-.030411,.027513,
-.030993,.022142,
-.031,.0215,
-.031,.015,
-.036,.015,
90.*
4,1,20,.031,.015,
.031,.0215,
.030529,.026882,
.029131,.032101,
.026847,.036998,
.023748,.041424,
.019928,.045244,
.015502,.048343,
.010605,.050627,
.01,.05084,
.01,.05608,
.015853,.053819,
.021224,.050576,
.025951,.046449,
.029889,.041565,
.032919,.03607,
.034949,.030133,
.035918,.023934,
.036,.0215,
.036,.015,
.031,.015,
90.*
%
%ADD21MACRO21*%
%ADD16C,.036*%
%AMMACRO22*
4,1,15,.00398,.00044,
.003999,.000208,
.004004,-.000025,
.003996,-.000258,
.00398,-.00044,
.00483,-.00129,
.004897,-.001007,
.004947,-.000721,
.004981,-.000432,
.004997,-.000141,
.004997,.000149,
.00498,.00044,
.004946,.000729,
.004895,.001015,
.00483,.00129,
.00398,.00044,
90.*
4,1,15,.00044,-.00398,
.000208,-.003999,
-.000025,-.004004,
-.000258,-.003996,
-.00044,-.00398,
-.00129,-.00483,
-.001007,-.004897,
-.000721,-.004947,
-.000432,-.004981,
-.000141,-.004997,
.000149,-.004997,
.00044,-.00498,
.000729,-.004946,
.001015,-.004895,
.00129,-.00483,
.00044,-.00398,
90.*
4,1,15,-.00398,-.00044,
-.003999,-.000208,
-.004004,.000025,
-.003996,.000258,
-.00398,.00044,
-.00483,.00129,
-.004897,.001007,
-.004947,.000721,
-.004981,.000432,
-.004997,.000141,
-.004997,-.000149,
-.00498,-.00044,
-.004946,-.000729,
-.004895,-.001015,
-.00483,-.00129,
-.00398,-.00044,
90.*
4,1,15,-.00044,.00398,
-.000208,.003999,
.000025,.004004,
.000258,.003996,
.00044,.00398,
.00129,.00483,
.001007,.004897,
.000721,.004947,
.000432,.004981,
.000141,.004997,
-.000149,.004997,
-.00044,.00498,
-.000729,.004946,
-.001015,.004895,
-.00129,.00483,
-.00044,.00398,
90.*
%
%ADD22MACRO22*%
%AMMACRO11*
4,1,15,.00398,.00044,
.003999,.000208,
.004004,-.000025,
.003996,-.000258,
.00398,-.00044,
.00483,-.00129,
.004897,-.001007,
.004947,-.000721,
.004981,-.000432,
.004997,-.000141,
.004997,.000149,
.00498,.00044,
.004946,.000729,
.004895,.001015,
.00483,.00129,
.00398,.00044,
0.0*
4,1,15,.00044,-.00398,
.000208,-.003999,
-.000025,-.004004,
-.000258,-.003996,
-.00044,-.00398,
-.00129,-.00483,
-.001007,-.004897,
-.000721,-.004947,
-.000432,-.004981,
-.000141,-.004997,
.000149,-.004997,
.00044,-.00498,
.000729,-.004946,
.001015,-.004895,
.00129,-.00483,
.00044,-.00398,
0.0*
4,1,15,-.00398,-.00044,
-.003999,-.000208,
-.004004,.000025,
-.003996,.000258,
-.00398,.00044,
-.00483,.00129,
-.004897,.001007,
-.004947,.000721,
-.004981,.000432,
-.004997,.000141,
-.004997,-.000149,
-.00498,-.00044,
-.004946,-.000729,
-.004895,-.001015,
-.00483,-.00129,
-.00398,-.00044,
0.0*
4,1,15,-.00044,.00398,
-.000208,.003999,
.000025,.004004,
.000258,.003996,
.00044,.00398,
.00129,.00483,
.001007,.004897,
.000721,.004947,
.000432,.004981,
.000141,.004997,
-.000149,.004997,
-.00044,.00498,
-.000729,.004946,
-.001015,.004895,
-.00129,.00483,
-.00044,.00398,
0.0*
%
%ADD11MACRO11*%
%ADD18C,.101*%
%ADD10C,.114*%
%AMMACRO17*
4,1,20,-.01,-.05608,
-.015853,-.053819,
-.021224,-.050576,
-.025951,-.046449,
-.029889,-.041565,
-.032919,-.03607,
-.034949,-.030133,
-.035918,-.023934,
-.036,-.0215,
-.036,-.015,
-.031,-.015,
-.031,-.0215,
-.030529,-.026882,
-.029131,-.032101,
-.026847,-.036998,
-.023748,-.041424,
-.019928,-.045244,
-.015502,-.048343,
-.010605,-.050627,
-.01,-.05084,
-.01,-.05608,
270.*
4,1,20,.01,-.05608,
.01,-.05084,
.014943,-.048658,
.019432,-.045652,
.023331,-.041911,
.026521,-.03755,
.028905,-.032702,
.030411,-.027513,
.030993,-.022142,
.031,-.0215,
.031,-.015,
.036,-.015,
.036,-.0215,
.035453,-.027751,
.033829,-.033811,
.031177,-.039498,
.027579,-.044638,
.023142,-.049074,
.018002,-.052673,
.012316,-.055325,
.01,-.05608,
270.*
4,1,20,-.036,.015,
-.036,.0215,
-.035453,.027751,
-.033829,.033811,
-.031177,.039498,
-.027579,.044638,
-.023142,.049074,
-.018002,.052673,
-.012316,.055325,
-.01,.05608,
-.01,.05084,
-.014943,.048658,
-.019432,.045652,
-.023331,.041911,
-.026521,.03755,
-.028905,.032702,
-.030411,.027513,
-.030993,.022142,
-.031,.0215,
-.031,.015,
-.036,.015,
270.*
4,1,20,.031,.015,
.031,.0215,
.030529,.026882,
.029131,.032101,
.026847,.036998,
.023748,.041424,
.019928,.045244,
.015502,.048343,
.010605,.050627,
.01,.05084,
.01,.05608,
.015853,.053819,
.021224,.050576,
.025951,.046449,
.029889,.041565,
.032919,.03607,
.034949,.030133,
.035918,.023934,
.036,.0215,
.036,.015,
.031,.015,
270.*
%
%ADD17MACRO17*%
%ADD14C,.119*%
%ADD23C,.174*%
%AMMACRO20*
4,1,15,.00398,.00044,
.003999,.000208,
.004004,-.000025,
.003996,-.000258,
.00398,-.00044,
.00483,-.00129,
.004897,-.001007,
.004947,-.000721,
.004981,-.000432,
.004997,-.000141,
.004997,.000149,
.00498,.00044,
.004946,.000729,
.004895,.001015,
.00483,.00129,
.00398,.00044,
180.*
4,1,15,.00044,-.00398,
.000208,-.003999,
-.000025,-.004004,
-.000258,-.003996,
-.00044,-.00398,
-.00129,-.00483,
-.001007,-.004897,
-.000721,-.004947,
-.000432,-.004981,
-.000141,-.004997,
.000149,-.004997,
.00044,-.00498,
.000729,-.004946,
.001015,-.004895,
.00129,-.00483,
.00044,-.00398,
180.*
4,1,15,-.00398,-.00044,
-.003999,-.000208,
-.004004,.000025,
-.003996,.000258,
-.00398,.00044,
-.00483,.00129,
-.004897,.001007,
-.004947,.000721,
-.004981,.000432,
-.004997,.000141,
-.004997,-.000149,
-.00498,-.00044,
-.004946,-.000729,
-.004895,-.001015,
-.00483,-.00129,
-.00398,-.00044,
180.*
4,1,15,-.00044,.00398,
-.000208,.003999,
.000025,.004004,
.000258,.003996,
.00044,.00398,
.00129,.00483,
.001007,.004897,
.000721,.004947,
.000432,.004981,
.000141,.004997,
-.000149,.004997,
-.00044,.00498,
-.000729,.004946,
-.001015,.004895,
-.00129,.00483,
-.00044,.00398,
180.*
%
%ADD20MACRO20*%
%AMMACRO12*
4,1,15,.00398,.00044,
.003999,.000208,
.004004,-.000025,
.003996,-.000258,
.00398,-.00044,
.00483,-.00129,
.004897,-.001007,
.004947,-.000721,
.004981,-.000432,
.004997,-.000141,
.004997,.000149,
.00498,.00044,
.004946,.000729,
.004895,.001015,
.00483,.00129,
.00398,.00044,
270.*
4,1,15,.00044,-.00398,
.000208,-.003999,
-.000025,-.004004,
-.000258,-.003996,
-.00044,-.00398,
-.00129,-.00483,
-.001007,-.004897,
-.000721,-.004947,
-.000432,-.004981,
-.000141,-.004997,
.000149,-.004997,
.00044,-.00498,
.000729,-.004946,
.001015,-.004895,
.00129,-.00483,
.00044,-.00398,
270.*
4,1,15,-.00398,-.00044,
-.003999,-.000208,
-.004004,.000025,
-.003996,.000258,
-.00398,.00044,
-.00483,.00129,
-.004897,.001007,
-.004947,.000721,
-.004981,.000432,
-.004997,.000141,
-.004997,-.000149,
-.00498,-.00044,
-.004946,-.000729,
-.004895,-.001015,
-.00483,-.00129,
-.00398,-.00044,
270.*
4,1,15,-.00044,.00398,
-.000208,.003999,
.000025,.004004,
.000258,.003996,
.00044,.00398,
.00129,.00483,
.001007,.004897,
.000721,.004947,
.000432,.004981,
.000141,.004997,
-.000149,.004997,
-.00044,.00498,
-.000729,.004946,
-.001015,.004895,
-.00129,.00483,
-.00044,.00398,
270.*
%
%ADD12MACRO12*%
%AMMACRO13*
4,1,16,.07256,.04427,
.079145,.030998,
.083325,.016783,
.084974,.002059,
.08404,-.012728,
.080553,-.027128,
.074619,-.040704,
.07256,-.04427,
.07619,-.04791,
.083352,-.033952,
.087981,-.018962,
.089937,-.003396,
.089161,.012273,
.085675,.027569,
.079586,.042027,
.07619,.04791,
.07256,.04427,
0.0*
4,1,16,.04427,-.07256,
.030998,-.079145,
.016783,-.083325,
.002059,-.084974,
-.012728,-.08404,
-.027128,-.080553,
-.040704,-.074619,
-.04427,-.07256,
-.04791,-.07619,
-.033952,-.083352,
-.018962,-.087981,
-.003396,-.089937,
.012273,-.089161,
.027569,-.085675,
.042027,-.079586,
.04791,-.07619,
.04427,-.07256,
0.0*
4,1,16,-.07256,-.04427,
-.079145,-.030998,
-.083325,-.016783,
-.084974,-.002059,
-.08404,.012728,
-.080553,.027128,
-.074619,.040704,
-.07256,.04427,
-.07619,.04791,
-.083352,.033952,
-.087981,.018962,
-.089937,.003396,
-.089161,-.012273,
-.085675,-.027569,
-.079586,-.042027,
-.07619,-.04791,
-.07256,-.04427,
0.0*
4,1,16,-.04427,.07256,
-.030998,.079145,
-.016783,.083325,
-.002059,.084974,
.012728,.08404,
.027128,.080553,
.040704,.074619,
.04427,.07256,
.04791,.07619,
.033952,.083352,
.018962,.087981,
.003396,.089937,
-.012273,.089161,
-.027569,.085675,
-.042027,.079586,
-.04791,.07619,
-.04427,.07256,
0.0*
%
%ADD13MACRO13*%
%ADD24C,.02*%
%ADD25C,.006*%
%ADD31R,.142X.028*%
%ADD27C,.09706*%
%ADD29R,.075X.02*%
%ADD30R,.094X.026*%
%ADD26C,.11506*%
%ADD28C,.17006*%
%ADD32R,.07509X.0691*%
G75*
%LPD*%
G75*
G36*
G01X-6000Y-6000D02*
X1039465D01*
Y1998126D01*
X-6000D01*
Y-6000D01*
G37*
%LPC*%
G75*
G36*
G01X1029528Y1989122D02*
G02X1030461Y1988189I0J-933D01*
G01Y1686599D01*
X1028283Y1684421D01*
X1023228D01*
G03X1016287Y1677480I0J-6941D01*
G01Y1621265D01*
X1014109Y1619087D01*
X989744D01*
G03Y1608866I0J-5110D01*
G01X1014109D01*
X1016287Y1606688D01*
Y1432756D01*
G03X1023228Y1425815I6941J0D01*
G01X1028283D01*
X1030461Y1423637D01*
Y3937D01*
G02X1029528Y3004I-933J0D01*
G01X3937D01*
G02X3004Y3937I0J933D01*
G01Y408401D01*
X5182Y410579D01*
X19882D01*
G03Y424067I0J6744D01*
G01X19668D01*
Y424628D01*
X5468D01*
Y424067D01*
X5182D01*
X3004Y426245D01*
Y817849D01*
X5182Y820027D01*
X19882D01*
G03Y833516I0J6745D01*
G01X5182D01*
X3004Y835694D01*
Y1392653D01*
X5182Y1394831D01*
X19882D01*
G03Y1408319I0J6744D01*
G01X19668D01*
Y1408880D01*
X5468D01*
Y1408319D01*
X5182D01*
X3004Y1410497D01*
Y1802101D01*
X5182Y1804279D01*
X19882D01*
G03Y1817768I0J6744D01*
G01X5182D01*
X3004Y1819946D01*
Y1988189D01*
G02X3937Y1989122I933J0D01*
G01X1029528D01*
G37*
%LPD*%
G75*
G54D31*
X12568Y383857D03*
Y387794D03*
Y399605D03*
Y403542D03*
Y427165D03*
Y438977D03*
Y442914D03*
Y454725D03*
Y458662D03*
Y470473D03*
Y474410D03*
Y486221D03*
Y490158D03*
Y501969D03*
Y505906D03*
Y517717D03*
Y521654D03*
Y533465D03*
Y537402D03*
Y568898D03*
Y572835D03*
Y620079D03*
Y624016D03*
Y635827D03*
Y639764D03*
Y651575D03*
Y655512D03*
Y667323D03*
Y671260D03*
Y1368109D03*
Y1372046D03*
Y1383857D03*
Y1387794D03*
Y1411417D03*
Y1423229D03*
Y1427166D03*
Y1438977D03*
Y1442914D03*
Y1454725D03*
Y1458662D03*
Y1470473D03*
Y1474410D03*
Y1486221D03*
Y1490158D03*
Y1501969D03*
Y1505906D03*
Y1517717D03*
Y1521654D03*
Y1553150D03*
Y1557087D03*
Y1604331D03*
Y1608268D03*
Y1620079D03*
Y1624016D03*
Y1635827D03*
Y1639764D03*
Y1651575D03*
Y1655512D03*
Y1667323D03*
Y1671260D03*
G54D27*
X78150Y28858D03*
Y178464D03*
Y434370D03*
Y583976D03*
Y839882D03*
Y989488D03*
Y1245394D03*
Y1395000D03*
Y1650906D03*
Y1800512D03*
X158071Y191614D03*
Y341220D03*
Y597126D03*
Y746732D03*
Y1002638D03*
Y1152244D03*
Y1408150D03*
Y1557756D03*
Y1813662D03*
Y1963268D03*
X886417Y191614D03*
Y341220D03*
Y597126D03*
Y746732D03*
Y1002638D03*
Y1152244D03*
Y1408150D03*
Y1557756D03*
Y1813662D03*
Y1963268D03*
G54D29*
X77165Y117349D03*
Y120498D03*
Y126798D03*
Y129947D03*
X159054Y240105D03*
X887400D03*
X159054Y243254D03*
X887400D03*
X159054Y249554D03*
X887400D03*
X159054Y252703D03*
X887400D03*
X77165Y522861D03*
Y526010D03*
Y532310D03*
Y535459D03*
X159054Y645617D03*
X887400D03*
X159054Y648766D03*
X887400D03*
X159054Y655066D03*
X887400D03*
X159054Y658215D03*
X887400D03*
X77165Y928373D03*
Y931522D03*
Y937822D03*
Y940971D03*
X159054Y1051129D03*
X887400D03*
X159054Y1054278D03*
X887400D03*
X159054Y1060578D03*
X887400D03*
X159054Y1063727D03*
X887400D03*
X77165Y1333885D03*
Y1337034D03*
Y1343334D03*
Y1346483D03*
X159054Y1456641D03*
X887400D03*
X159054Y1459790D03*
X887400D03*
X159054Y1466090D03*
X887400D03*
X159054Y1469239D03*
X887400D03*
X77165Y1739397D03*
Y1742546D03*
Y1748846D03*
Y1751995D03*
X159054Y1862153D03*
X887400D03*
X159054Y1865302D03*
X887400D03*
X159054Y1871602D03*
X887400D03*
X159054Y1874751D03*
X887400D03*
G54D30*
X85629Y141128D03*
Y146128D03*
Y156128D03*
Y161128D03*
X150590Y208924D03*
X878936D03*
X150590Y213924D03*
X878936D03*
X150590Y223924D03*
X878936D03*
X150590Y228924D03*
X878936D03*
X85629Y546640D03*
Y551640D03*
Y561640D03*
Y566640D03*
X150590Y614436D03*
X878936D03*
X150590Y619436D03*
X878936D03*
X150590Y629436D03*
X878936D03*
X150590Y634436D03*
X878936D03*
X85629Y952152D03*
Y957152D03*
Y967152D03*
Y972152D03*
X150590Y1019948D03*
X878936D03*
X150590Y1024948D03*
X878936D03*
X150590Y1034948D03*
X878936D03*
X150590Y1039948D03*
X878936D03*
X85629Y1357664D03*
Y1362664D03*
Y1372664D03*
Y1377664D03*
X150590Y1425460D03*
X878936D03*
X150590Y1430460D03*
X878936D03*
X150590Y1440460D03*
X878936D03*
X150590Y1445460D03*
X878936D03*
X85629Y1763176D03*
Y1768176D03*
Y1778176D03*
Y1783176D03*
X150590Y1830972D03*
X878936D03*
X150590Y1835972D03*
X878936D03*
X150590Y1845972D03*
X878936D03*
X150590Y1850972D03*
X878936D03*
G54D26*
X9843Y353144D03*
Y717711D03*
Y762617D03*
Y875216D03*
Y1337396D03*
Y1701963D03*
Y1746869D03*
Y1859468D03*
G54D28*
X1019291Y1416024D03*
Y1694212D03*
G54D32*
X860838Y1872869D03*
X130116Y1872510D03*
X860838Y1848369D03*
X130116Y1848010D03*
X105522Y1765806D03*
X103522Y1741306D03*
X858820Y1467538D03*
X129414Y1467497D03*
Y1442997D03*
X858820Y1442538D03*
X105852Y1360208D03*
X107474Y1346356D03*
X102352Y1335208D03*
X130973Y1079356D03*
X857320Y1062638D03*
X131022Y1061806D03*
X857320Y1037638D03*
X131022Y1037306D03*
X106568Y954745D03*
X101568Y929745D03*
X857720Y656638D03*
X133462Y656321D03*
X857720Y632138D03*
X133462Y631821D03*
X106968Y549244D03*
X102968Y524244D03*
X857501Y251180D03*
X130022Y250806D03*
X857501Y226680D03*
X130022Y226306D03*
X107022Y143306D03*
Y127806D03*
G54D19*
X129921Y17716D03*
X994093Y1889751D03*
G54D15*
X14999Y1936050D03*
X8499Y1937550D03*
X15099Y1944050D03*
X5303Y1947050D03*
X11703Y1951946D03*
X17499Y1961050D03*
X26299Y383854D03*
Y387629D03*
X28100Y374000D03*
X26299Y399601D03*
Y403376D03*
X35900Y412600D03*
X26524Y426720D03*
X26399Y423322D03*
X28900Y417800D03*
X26492Y439350D03*
X26599Y442749D03*
X26899Y454850D03*
X26799Y458497D03*
X26486Y462648D03*
X26499Y466250D03*
X26299Y478404D03*
X26515Y481798D03*
X36499Y517775D03*
X26399Y501966D03*
Y505741D03*
X36499Y521550D03*
X26599Y525648D03*
Y529302D03*
X27199Y539600D03*
X39217Y554750D03*
X33307Y557938D03*
X26199Y547176D03*
X29999Y557150D03*
X33699Y561850D03*
X36499Y566350D03*
X28000Y578500D03*
X25581Y567763D03*
X27699Y573750D03*
X28808Y593150D03*
X28700Y596549D03*
X27499Y620203D03*
Y623857D03*
X37999Y611550D03*
X26800Y611500D03*
X32200Y603710D03*
X31598Y607102D03*
X39600Y626984D03*
X38300Y633800D03*
X26568Y635950D03*
Y639604D03*
X26737Y651957D03*
X26999Y656550D03*
X27687Y667447D03*
Y671101D03*
X27700Y682700D03*
X27299Y783550D03*
X35300Y789375D03*
X32800Y803050D03*
X37416Y799033D03*
X37099Y811350D03*
X35559Y795112D03*
X31699Y814350D03*
X37216Y807951D03*
X39649Y822000D03*
X29299Y836901D03*
X40400Y840792D03*
X29600Y854000D03*
X23299Y863050D03*
X26662Y861550D03*
X25000Y858100D03*
X20999Y1320550D03*
Y1352050D03*
X25000Y1357742D03*
X25507Y1372045D03*
X25558Y1368447D03*
X28499Y1391050D03*
X32333Y1389383D03*
X30500Y1395500D03*
X32451Y1411468D03*
X28999Y1411550D03*
X32094Y1448448D03*
X28697Y1448296D03*
X33206Y1432352D03*
X30499Y1434550D03*
X30378Y1462518D03*
X33915Y1462681D03*
X34465Y1481683D03*
X30999Y1482050D03*
X34099Y1497550D03*
X30499D03*
X30115Y1511900D03*
X33512Y1512051D03*
X29631Y1533063D03*
X31999Y1517846D03*
Y1521500D03*
X37999Y1530900D03*
X24199Y1523700D03*
X38500Y1534600D03*
X32099Y1535550D03*
X26705Y1534795D03*
X30199Y1545450D03*
X36340Y1558809D03*
X34896Y1555730D03*
X38208Y1569841D03*
X25521Y1563350D03*
X30520Y1572049D03*
X27123Y1572205D03*
X39000Y1573500D03*
X34999Y1595350D03*
X28899Y1613524D03*
X32299D03*
X33599Y1600200D03*
X29499Y1630050D03*
X32663Y1628181D03*
X31999Y1661127D03*
X28600Y1661039D03*
X29626Y1645002D03*
X33026Y1645051D03*
X32700Y1673300D03*
X32494Y1669706D03*
X29100Y1669500D03*
X30500Y1697500D03*
X39900Y1751200D03*
X41200Y1747050D03*
X30274Y1787238D03*
X35675Y1783450D03*
X39324Y1780623D03*
X38094Y1785840D03*
X38878Y1799571D03*
X34599Y1805123D03*
X37699Y1789850D03*
X37574Y1794050D03*
X31811Y1790271D03*
X40478Y1795820D03*
X32099Y1797150D03*
X28550Y1828153D03*
X29899Y1821050D03*
X34099Y1822850D03*
X35876Y1812350D03*
X34129Y1815267D03*
X36532Y1825352D03*
X36399Y1828750D03*
X26099Y1824950D03*
X29599Y1844350D03*
X28123Y1831527D03*
X25999Y1842550D03*
X39699Y1833850D03*
X23030Y1922038D03*
X26765Y1921945D03*
X25499Y1956050D03*
X32999Y1960555D03*
X31799Y1979050D03*
X45800Y405200D03*
X61400Y452600D03*
X62497Y474346D03*
X60003Y534150D03*
X59999Y537550D03*
X42867Y548450D03*
X43099Y555850D03*
X46299Y552950D03*
X49799Y559150D03*
X42599Y567850D03*
X42202Y608195D03*
X41400Y611500D03*
X47626Y611300D03*
X45701Y607700D03*
X42709Y625607D03*
X41500Y642800D03*
X47101Y632355D03*
X41500Y635000D03*
X52500D03*
X48999Y642900D03*
X50410Y695801D03*
X50300Y699200D03*
X45100Y793100D03*
X44046Y799554D03*
X46887Y803413D03*
X51100Y806300D03*
X49900Y813200D03*
X56281Y801350D03*
X50399Y836250D03*
X46700Y820100D03*
X54074Y815750D03*
X62405Y820300D03*
X46576Y832951D03*
X48346Y844529D03*
X58699Y837250D03*
X44697Y1546793D03*
X44299Y1550950D03*
X42199Y1601050D03*
X45877Y1728477D03*
Y1724823D03*
X47000Y1737100D03*
X43600D03*
X42275Y1754000D03*
X45799Y1757650D03*
X47440Y1761391D03*
X47400Y1765250D03*
X43751Y1780559D03*
X46999Y1779550D03*
X46199Y1783050D03*
X43925Y1767890D03*
X47604Y1769005D03*
X45782Y1771877D03*
X47499Y1775350D03*
X47899Y1798650D03*
X48049Y1791450D03*
X42199Y1792250D03*
X46799Y1794900D03*
X61009Y1822340D03*
X46499Y1836550D03*
X47166Y1839884D03*
X43099Y1833850D03*
X57999Y1891050D03*
X42499Y1902550D03*
X48499Y1897050D03*
X50499Y1961550D03*
X43462Y1961160D03*
X78700Y74200D03*
Y70700D03*
X74999Y70550D03*
Y74050D03*
X74499Y80650D03*
Y84050D03*
X65999Y216050D03*
X65000Y455500D03*
X62503Y470946D03*
X62978Y486217D03*
X63067Y489616D03*
X65599Y514250D03*
X68000Y546500D03*
X72500Y545000D03*
X81251Y607249D03*
Y619251D03*
X82499Y627050D03*
X80499Y664550D03*
X76999D03*
X65500Y817700D03*
X80500Y817000D03*
X76540Y850938D03*
X75500Y847700D03*
X68860Y838706D03*
X69499Y842950D03*
X63499Y843050D03*
X74220Y854150D03*
X72362Y849550D03*
X80699Y1004450D03*
Y1000450D03*
X72000Y1013400D03*
X63273Y1023974D03*
X66499Y1025050D03*
X75500Y1012261D03*
X65486Y1031515D03*
X76999Y1196550D03*
X77758Y1357742D03*
X76000Y1431100D03*
X80043Y1544691D03*
X78600Y1561900D03*
X75000Y1561800D03*
X74400Y1574800D03*
X80400Y1571766D03*
X82329Y1568117D03*
X79000Y1555500D03*
X82429D03*
X74800Y1584700D03*
X74500Y1692000D03*
X74400Y1778100D03*
X80099Y1817250D03*
X80999Y1836550D03*
X97499Y90050D03*
X86899Y130567D03*
X86599Y126750D03*
X95350Y204550D03*
X89800Y208550D03*
X95500Y513400D03*
X98900D03*
X86199Y536025D03*
Y532250D03*
X89000Y816500D03*
X90000Y826000D03*
X90500Y831500D03*
X98700Y822550D03*
X98000Y833500D03*
X98700Y842600D03*
X94999Y901550D03*
X85999Y940429D03*
X86399Y937050D03*
X102100Y968500D03*
X99000Y965000D03*
X104600Y980500D03*
X90000Y993100D03*
X92600Y996100D03*
X88000Y1008500D03*
X101499Y1072550D03*
X103999Y1216863D03*
X102900Y1196050D03*
X103686Y1223863D03*
X101541Y1262607D03*
X101399Y1292550D03*
X102700Y1321363D03*
X86890Y1342860D03*
Y1346635D03*
X102350Y1344500D03*
Y1348154D03*
X97229Y1373337D03*
X97000Y1377600D03*
X98599Y1491350D03*
X100699Y1471050D03*
X83932Y1544705D03*
X100800Y1536450D03*
X96200Y1550100D03*
X99899Y1539850D03*
X100000Y1546650D03*
X90324Y1538800D03*
X97499Y1554550D03*
X98144Y1534309D03*
X96999Y1558050D03*
X89373Y1561073D03*
X85600Y1561500D03*
X95499Y1665418D03*
X93999Y1703050D03*
X85341Y1752245D03*
X85194Y1748848D03*
X99199Y1761899D03*
X99999Y1753575D03*
X101399Y1784700D03*
X85599Y1797350D03*
X96600Y1826000D03*
X86649Y1817100D03*
X90000Y1827900D03*
X93500D03*
X97999Y1843050D03*
X115876Y125973D03*
Y130050D03*
X122397Y252688D03*
X122799Y249150D03*
X107499Y497050D03*
X109400Y543200D03*
X106000D03*
X105100Y600000D03*
X107000Y604800D03*
X125499Y635550D03*
Y638950D03*
X110500Y790200D03*
X111100Y813400D03*
X111200Y799450D03*
X111207Y810001D03*
X110700Y795700D03*
X111089Y806603D03*
X110800Y803100D03*
X110499Y834550D03*
X108845Y931657D03*
X109099Y928250D03*
X108200Y963600D03*
X107300Y986000D03*
X107400Y992900D03*
X123999Y1054050D03*
Y1050650D03*
X116700Y1063500D03*
X112699Y1058974D03*
X105499Y1080550D03*
X106718Y1076050D03*
X105999Y1085800D03*
X105600Y1069500D03*
X124423Y1077523D03*
Y1081177D03*
X120749Y1093990D03*
X125900Y1091282D03*
X123999Y1102550D03*
X108999Y1102050D03*
X106999Y1194550D03*
X106162Y1205702D03*
X123970Y1221573D03*
X119399Y1298113D03*
X116999Y1288050D03*
X120507Y1317050D03*
X107999Y1307713D03*
X116499Y1328013D03*
X120507Y1328096D03*
X109228Y1337090D03*
Y1333315D03*
X119499Y1339050D03*
X112440Y1358196D03*
X112999Y1361550D03*
X121000Y1364000D03*
X113500Y1344500D03*
Y1348154D03*
X125100Y1366000D03*
X117390Y1426201D03*
Y1429976D03*
X104935Y1440634D03*
X104999Y1444941D03*
X124290Y1469241D03*
X123808Y1465050D03*
X106999Y1454450D03*
X118499Y1694050D03*
X117499Y1706050D03*
X109499Y1712213D03*
X112753Y1716613D03*
X122642Y1704243D03*
X112562Y1720613D03*
X123749Y1711550D03*
X109499Y1743550D03*
X109399Y1739550D03*
X110099Y1759875D03*
X123393Y1870859D03*
X123592Y1874254D03*
X141499Y427550D03*
Y423050D03*
X135499Y517550D03*
X137899Y545451D03*
X138416Y553500D03*
X140940Y561800D03*
X141300Y565900D03*
X127999Y645550D03*
X131400Y644600D03*
X144238Y645356D03*
Y649131D03*
X137481Y1077557D03*
X137477Y1081177D03*
X132499Y1094550D03*
X138600Y1124600D03*
X135850Y1322250D03*
X143700Y1332500D03*
X140000Y1332600D03*
X129000Y1356500D03*
X142999Y1456373D03*
X142900Y1460000D03*
X133090Y1699959D03*
X128749Y1703300D03*
X131999Y1710050D03*
X135499Y1710150D03*
X141999Y1764550D03*
X137999Y1861497D03*
Y1865151D03*
X154200Y168500D03*
X149400Y166400D03*
X149999Y243504D03*
Y239729D03*
X159600Y446399D03*
X163549Y517100D03*
X152000Y520813D03*
X149000Y537500D03*
X150500Y545000D03*
X150750Y540416D03*
X156500Y554000D03*
X157000Y573851D03*
X160824Y577000D03*
X165499Y815550D03*
X153500Y834600D03*
X154799Y838050D03*
X153499Y918550D03*
X163500Y937100D03*
X152500Y960000D03*
X154749Y979149D03*
Y968249D03*
X164700Y1085400D03*
X147400Y1321600D03*
X148024Y1333525D03*
X157400Y1596550D03*
X160200Y1598500D03*
X152633Y1677967D03*
X150999Y1713550D03*
X165900Y1790500D03*
X161900Y1793400D03*
X174999Y79050D03*
X175499Y86572D03*
X176399Y94872D03*
X178999Y79050D03*
X186999Y99050D03*
X188999Y120800D03*
X173500Y166315D03*
X187699Y492850D03*
X172499Y491053D03*
X176799Y493850D03*
X188000Y484500D03*
X171722Y513827D03*
X183499Y556100D03*
X169106Y815865D03*
X172500Y919294D03*
X172000Y931600D03*
X171100Y935000D03*
X171000Y939500D03*
X172000Y961000D03*
X170250Y948500D03*
X179499Y1275550D03*
X181000Y1365500D03*
X180500Y1369900D03*
X171999Y1662250D03*
X169600Y1682300D03*
X169100Y1685800D03*
X174250Y1694500D03*
X181100Y1682700D03*
X177900Y1690400D03*
X205499Y105550D03*
X207999Y109550D03*
X199900Y554050D03*
X200799Y896600D03*
X199149Y1362900D03*
X194700Y1385700D03*
X201499Y1781050D03*
X225499Y68550D03*
X230749Y76300D03*
X213499Y104650D03*
X223499Y108150D03*
X218499Y190550D03*
X225298Y281114D03*
X220000Y516400D03*
X211750Y894600D03*
X221800Y1069300D03*
X229800Y1073600D03*
X226800Y1093400D03*
X224750Y1483950D03*
X229025Y1471576D03*
X227814Y1887513D03*
X223436Y1890465D03*
X229800Y1875700D03*
X218100Y1886400D03*
X214999Y1909550D03*
X213138Y1952703D03*
X210999Y1942050D03*
X233749Y110800D03*
X237899Y107050D03*
X247800Y269700D03*
X250300Y275100D03*
X250400Y283100D03*
X239600Y278600D03*
X246800Y677100D03*
X249700Y682500D03*
X238500Y680800D03*
X249800Y689900D03*
X233500Y1066100D03*
X242000Y1066000D03*
X247500Y1085500D03*
X251500Y1136700D03*
X241000Y1469600D03*
X233700Y1481600D03*
X231800Y1887100D03*
X231999Y1914050D03*
X249600Y1896800D03*
X249499Y1928050D03*
X253871Y291410D03*
X254499Y697700D03*
X269500Y1135500D03*
X261999Y1516050D03*
X257499Y1911050D03*
X264499Y1964050D03*
X282800Y87500D03*
X293999Y293550D03*
X284999Y338650D03*
X281499Y338550D03*
X279939Y728610D03*
X285499Y745050D03*
X282099D03*
X282500Y1135000D03*
X295000Y1513000D03*
X283499Y1556050D03*
X279999D03*
X285499Y1930050D03*
X288709Y1948042D03*
X284999Y1947691D03*
X308999Y87050D03*
X297499Y97550D03*
X315800Y100500D03*
X301249Y346050D03*
X310999Y757050D03*
X310249Y1569800D03*
X310499Y1957050D03*
X324800Y89400D03*
X323400Y105200D03*
X326499Y334054D03*
Y337454D03*
X327999Y740550D03*
X327749Y744050D03*
X329499Y801550D03*
X330540Y795509D03*
X320499Y798050D03*
X326500Y1550200D03*
X330300Y1561200D03*
X331622Y1944767D03*
X332103Y1948133D03*
X343499Y31650D03*
X354999Y72050D03*
X341499Y63050D03*
Y67110D03*
X344520Y406329D03*
X350499Y597300D03*
Y715050D03*
X340699Y1046086D03*
X345499Y1096550D03*
X345424Y1310050D03*
X347324Y1524000D03*
X354500Y1559500D03*
X349774Y1582900D03*
X354000Y1584900D03*
X353499Y1710450D03*
X348499Y1762050D03*
X342999Y1947409D03*
X342621Y1943409D03*
X358999Y61550D03*
X365499Y86550D03*
X371999Y549300D03*
X375999Y698550D03*
X371500Y880600D03*
X364499Y1099050D03*
X372999Y1123550D03*
X370149Y1320050D03*
X366149Y1554050D03*
X377900Y1703800D03*
X381999Y53550D03*
X394199Y45050D03*
X381999Y57050D03*
X400499Y406329D03*
X394649Y630600D03*
X390999Y1514398D03*
Y1517798D03*
X385499Y1735050D03*
X402499Y1476850D03*
X400999Y1575550D03*
X645549Y1815134D03*
X644360Y1819137D03*
X707600Y1815600D03*
X711652Y1822109D03*
X711848Y1825504D03*
X732549Y1806634D03*
X733149Y1798634D03*
X733049Y1814134D03*
X757499Y1079550D03*
X757999Y1484050D03*
X758499Y1893550D03*
X772499Y323050D03*
X772873Y326924D03*
X780499Y330050D03*
X771105Y722789D03*
X769999Y733050D03*
X771999Y1124550D03*
X772499Y1130050D03*
X779499Y1131050D03*
X774542Y1530050D03*
X774577Y1533796D03*
X771499Y1936550D03*
Y1940050D03*
X791499Y333050D03*
X789999Y336550D03*
X781999Y725550D03*
X788999Y736050D03*
X791999Y733050D03*
X792154Y1135926D03*
X789499Y1138050D03*
X784499Y1529050D03*
X791499Y1543550D03*
X793999Y1541050D03*
X793000Y1803500D03*
X795849Y1805500D03*
X802499Y1951550D03*
X800431Y1941193D03*
X792499Y1949050D03*
X794499Y1941050D03*
X782999Y1937050D03*
X802099Y1961950D03*
X809940Y264940D03*
X822100Y261700D03*
Y279500D03*
X816700Y274300D03*
X820600Y664300D03*
X808660Y667540D03*
X813200Y675900D03*
X807000Y1072900D03*
X815400Y1078800D03*
X803199Y1151850D03*
X822100Y1466800D03*
X809960Y1478040D03*
X814700Y1486300D03*
X804899Y1556950D03*
X807000Y1822300D03*
X803500Y1822708D03*
X822700Y1871100D03*
X810900Y1882440D03*
X805900Y1887560D03*
X829917Y216200D03*
X833576Y215432D03*
X837999Y219550D03*
X842499Y280924D03*
X827500Y274500D03*
X829800Y666650D03*
X825700Y1083100D03*
X825800Y1072300D03*
X827700Y1487600D03*
X828500Y1877800D03*
X834799Y1946950D03*
X854400Y264600D03*
X847878Y250040D03*
X851278Y249974D03*
X865499Y288050D03*
X851172Y655432D03*
X847772Y655370D03*
X852696Y671197D03*
X850833Y1061441D03*
X847233Y1061492D03*
X852333Y1077716D03*
X864499Y1128750D03*
X861849Y1376050D03*
X848888Y1466402D03*
X852288Y1466346D03*
X854327Y1477550D03*
X863699Y1501250D03*
X862800Y1712700D03*
X853499Y1871036D03*
X850099Y1871056D03*
X854814Y1883550D03*
X863699Y1906450D03*
X857099Y1917650D03*
X867500Y163924D03*
X867576Y159924D03*
X878078Y240103D03*
Y243878D03*
X868799Y294750D03*
X867899Y321550D03*
X868299Y336150D03*
X879750Y570550D03*
X879950Y565050D03*
X878596Y645573D03*
Y649348D03*
X883083Y979183D03*
X879708Y971892D03*
X878233Y1051095D03*
X877964Y1054485D03*
X866700Y1379796D03*
X866596Y1375796D03*
X878054Y1456450D03*
X877853Y1459991D03*
X867523Y1542821D03*
X867199Y1535150D03*
X886439Y1717600D03*
X873800Y1733600D03*
X879700Y1786300D03*
X879664Y1782213D03*
X866914Y1861840D03*
Y1865615D03*
X901499Y92050D03*
X897555Y90494D03*
X902499Y110550D03*
X898999D03*
X907499Y131800D03*
X902999Y556050D03*
X900499Y962100D03*
X900999Y979050D03*
X889800Y1711500D03*
X926999Y115050D03*
Y122050D03*
X910999Y124550D03*
X916499Y172550D03*
X917499Y1796550D03*
X943499Y82550D03*
X930999Y115550D03*
X938499D03*
X937999Y122050D03*
X934499Y118750D03*
X961499Y93350D03*
X965150Y1639500D03*
X961702Y1636102D03*
X969600Y1638300D03*
X967600Y1651100D03*
X971558Y1646500D03*
X986400Y1639302D03*
X987100Y1624900D03*
X981200Y1625800D03*
X977500Y1660500D03*
X981500Y1653000D03*
X980800Y1659600D03*
X982050Y1649302D03*
X978000Y1668000D03*
X974000Y1670700D03*
X984211Y1667500D03*
G54D21*
X167323Y179803D03*
Y353031D03*
Y585315D03*
Y758543D03*
Y990827D03*
Y1164055D03*
Y1396339D03*
Y1569567D03*
Y1801851D03*
Y1975079D03*
X895669Y179803D03*
Y353031D03*
Y585315D03*
Y758543D03*
Y990827D03*
Y1164055D03*
Y1396339D03*
Y1569567D03*
Y1801851D03*
Y1975079D03*
G54D16*
X36999Y725050D03*
Y719550D03*
X37499Y714050D03*
X41499Y719550D03*
X36499Y740050D03*
Y732550D03*
X43499Y657550D03*
X50999Y720050D03*
X46499Y719550D03*
X51499Y724550D03*
X46499D03*
X41999D03*
X46499Y730550D03*
X41999Y735050D03*
Y731050D03*
X46499Y735050D03*
X41999Y739550D03*
X46499Y739050D03*
X51999Y767050D03*
X47999Y767550D03*
X52499Y771550D03*
X47999D03*
X47499Y1915050D03*
Y1930550D03*
X62499Y1939550D03*
X58999Y1958050D03*
X67000Y1011500D03*
X81499Y1589050D03*
X83499Y1594050D03*
X78999Y1593550D03*
X74999D03*
X74499Y1602050D03*
Y1598050D03*
X83499D03*
Y1602050D03*
X78999Y1598050D03*
Y1602050D03*
Y1891550D03*
X82999D03*
Y1887550D03*
X78999D03*
X62999Y1914550D03*
X78999Y1896050D03*
X78433Y1900010D03*
X78999Y1904050D03*
X83499Y1896050D03*
X83433Y1904010D03*
X62999Y1926050D03*
X81499Y1915550D03*
X82499Y1957050D03*
X73499D03*
X66499D03*
X73499Y1945550D03*
X96999Y49550D03*
X92999Y52050D03*
X97800Y36000D03*
X96900Y40400D03*
X93000Y44900D03*
X92900Y39700D03*
X97999Y199050D03*
X93500Y445300D03*
X97699Y449850D03*
X93199D03*
X97999Y445550D03*
X94500Y456800D03*
X100500Y456700D03*
X98999Y488050D03*
X94499Y486550D03*
X93499Y477050D03*
X97699Y481550D03*
Y477050D03*
X93499Y481550D03*
X98001Y856950D03*
X97800Y851800D03*
X93808Y852063D03*
X94001Y856895D03*
X97499Y862050D03*
X93299D03*
X93900Y882400D03*
X97900D03*
X97700Y887400D03*
X93690Y887139D03*
X97499Y892550D03*
X93499Y892050D03*
X100999Y1101050D03*
X104999D03*
X100999Y1096550D03*
X97300Y1564100D03*
X92499Y1589050D03*
X86999D03*
X83999Y1900050D03*
Y1945050D03*
X98433Y1940510D03*
X98999Y1944550D03*
X102433Y1940555D03*
X103433Y1944510D03*
X92499Y1959050D03*
X116400Y56000D03*
X114800Y68500D03*
X105006Y1096866D03*
X110999Y1130550D03*
X115200Y1130300D03*
X110999Y1126050D03*
Y1122050D03*
Y1118050D03*
X114999Y1126050D03*
Y1122050D03*
Y1118050D03*
X123500Y1360300D03*
X122600Y1565000D03*
X105749Y1712749D03*
X124433Y1908510D03*
X124999Y1912550D03*
X119999Y1978550D03*
X119499Y1972550D03*
X129100Y55900D03*
X127499Y65050D03*
X141999Y65550D03*
X129999Y78050D03*
X127999Y99550D03*
Y425050D03*
Y421050D03*
Y429550D03*
X135999Y472550D03*
X135140Y478930D03*
X145649Y509550D03*
X136349Y509050D03*
X140499Y499050D03*
X136299D03*
X147300Y526700D03*
X144149Y1230113D03*
Y1226113D03*
Y1222113D03*
X129100Y1564700D03*
X127200Y1569800D03*
X130499Y1730050D03*
X128000Y1735000D03*
X144499Y1729550D03*
X139500Y1730500D03*
X133000Y1734500D03*
X129999Y1908550D03*
X129433Y1912510D03*
X127499Y1978550D03*
X133499D03*
X132999Y1972550D03*
X126999D03*
X167499Y43550D03*
X156499Y66050D03*
X166999Y88050D03*
X166499Y83550D03*
Y79050D03*
X158499D03*
Y84050D03*
Y88550D03*
Y93550D03*
X166999Y92550D03*
X165499Y106050D03*
X166999Y97050D03*
X155999Y181050D03*
X149700Y471600D03*
X154100Y476500D03*
X164600Y476700D03*
X153499Y502550D03*
X148999D03*
X147590Y521500D03*
X161999Y768050D03*
X152499Y810550D03*
Y816050D03*
Y820550D03*
Y825050D03*
X156499Y870550D03*
Y876050D03*
X163999Y863050D03*
X159999D03*
X155999Y859050D03*
Y863050D03*
X159459Y896616D03*
X163499Y896550D03*
X155499Y891050D03*
Y896050D03*
X157499Y904550D03*
Y909050D03*
X151999Y936550D03*
X152499Y931550D03*
X159186Y946117D03*
X151300Y1049300D03*
X148499Y1222113D03*
Y1226113D03*
X148486Y1230113D03*
X167499Y1714113D03*
X162499D03*
X165499Y1730613D03*
X167999Y1726613D03*
X163499D03*
X189499Y39150D03*
X183499Y45550D03*
X169999Y103050D03*
X179999Y442550D03*
X179649Y438550D03*
X183999D03*
Y442550D03*
Y447050D03*
X179999D03*
X171300Y476700D03*
X187499Y531613D03*
Y536113D03*
X188999Y541113D03*
Y549613D03*
Y545613D03*
X175823Y1297070D03*
X179999Y1301550D03*
Y1292550D03*
X175499D03*
X179999Y1296613D03*
X175499Y1302113D03*
X179999Y1306050D03*
X175499Y1306113D03*
X180299Y1626550D03*
X180000Y1619600D03*
X180299Y1634550D03*
X179733Y1630590D03*
X172499Y1714050D03*
X170499Y1731050D03*
X172499Y1726613D03*
X197999Y39900D03*
X193999D03*
X208499Y45650D03*
X199999Y46050D03*
X194499Y44050D03*
X192499Y57550D03*
X194999Y490050D03*
X190499Y487550D03*
X191199Y491550D03*
X193499Y541113D03*
Y549613D03*
X193999Y545550D03*
X204496Y846111D03*
X204649Y838050D03*
X208999D03*
X209000Y846113D03*
X204649Y842113D03*
X208986D03*
X195700Y1619100D03*
X195600Y1623700D03*
X225499Y52550D03*
Y46550D03*
Y63550D03*
Y58050D03*
X227999Y178050D03*
X227499Y192050D03*
X227999Y187050D03*
Y182550D03*
X215999Y887550D03*
X220499D03*
X215499Y883550D03*
X219499Y939613D03*
X214999D03*
X219499Y926613D03*
X214999D03*
X219499Y948613D03*
Y943813D03*
X214999Y944113D03*
Y948613D03*
X226999Y1941050D03*
X231999Y178050D03*
Y192050D03*
Y187050D03*
Y182550D03*
X267498Y305114D03*
Y300114D03*
Y295114D03*
Y310114D03*
X268499Y701550D03*
Y706550D03*
Y716550D03*
Y711550D03*
X272499Y1153050D03*
X268499D03*
X263999D03*
X259999Y1152992D03*
X271999Y1161550D03*
X267999D03*
X263499D03*
X259499D03*
X260999Y1503550D03*
X266999Y1512550D03*
X267349Y1518150D03*
Y1522550D03*
Y1527172D03*
X266999Y1915550D03*
Y1920050D03*
Y1924550D03*
Y1929050D03*
Y1933550D03*
X294100Y28000D03*
X289499Y39050D03*
X286603Y34928D03*
X289999Y72550D03*
X290999Y67550D03*
X288499Y76550D03*
X289499Y80550D03*
X279998Y304114D03*
Y299614D03*
Y295114D03*
Y308614D03*
X293998Y361114D03*
Y356614D03*
Y352114D03*
X289998Y361114D03*
Y356614D03*
Y352114D03*
X280999Y701550D03*
Y705550D03*
Y717550D03*
X280433Y713590D03*
X294999Y767050D03*
X290999D03*
X294999Y762550D03*
Y758050D03*
X290999Y762550D03*
Y758050D03*
X279499Y1510550D03*
Y1515050D03*
X279075Y1525957D03*
X278567Y1529925D03*
X293998Y1573614D03*
Y1569114D03*
X289998Y1573614D03*
Y1569114D03*
X293998Y1578114D03*
X289998D03*
X293999Y1933050D03*
X281999Y1918550D03*
Y1923550D03*
Y1928550D03*
X293999Y1971050D03*
Y1966550D03*
Y1962050D03*
X289499Y1961550D03*
Y1966550D03*
Y1971050D03*
X304500Y44500D03*
X303300Y39500D03*
X308700Y39800D03*
X308800Y46400D03*
X308499Y72550D03*
X303999Y74050D03*
X307999Y78550D03*
X305998Y352114D03*
X306999Y758050D03*
X305998Y1569114D03*
X306999Y1932550D03*
X302499D03*
X298499D03*
X305999Y1964050D03*
Y1969550D03*
X326301Y1766030D03*
X334999Y1797050D03*
X356499Y113050D03*
X351999D03*
X347499D03*
X355999Y100550D03*
X350999D03*
X345999D03*
X371999Y15550D03*
X376499D03*
X369999Y23550D03*
Y19050D03*
X376999Y65550D03*
Y70050D03*
X360999Y113050D03*
Y100550D03*
X380999Y15550D03*
X382499Y20050D03*
X381499Y65550D03*
Y70050D03*
X544300Y1784638D03*
X557999Y322550D03*
Y326550D03*
X558099Y335050D03*
X557933Y331010D03*
X558499Y616050D03*
X554304Y615840D03*
X554499Y624550D03*
X558699D03*
X554499Y620050D03*
X558709Y620245D03*
X563499Y1486550D03*
Y1492050D03*
Y1497550D03*
Y1503550D03*
X633837Y1807384D03*
X717000Y1812384D03*
X757999Y154550D03*
Y159050D03*
X753999Y154550D03*
Y159050D03*
X755499Y314550D03*
X755346Y319149D03*
X751539Y313984D03*
X751499Y318050D03*
Y679148D03*
X749499Y716050D03*
X744999Y715550D03*
X749999Y720050D03*
X745499D03*
X755499Y1119050D03*
X749999Y1119550D03*
X748999Y1115550D03*
X748499Y1111550D03*
X751000Y1517000D03*
X757500Y1522500D03*
X751000Y1521000D03*
Y1525000D03*
X756900Y1766000D03*
X752900D03*
X751999Y1775550D03*
X756617Y1780067D03*
X752657Y1779496D03*
X755999Y1775550D03*
X753558Y1769946D03*
X757518Y1770517D03*
X781478Y363924D03*
X776978D03*
X772478Y359924D03*
Y363924D03*
X771196Y764382D03*
Y760382D03*
X775696Y764382D03*
X780196D03*
X780333Y1165892D03*
X775833D03*
X771333Y1161892D03*
Y1165892D03*
X778327Y1569796D03*
X773327Y1565796D03*
X773827Y1569796D03*
X767159Y1792364D03*
X773999Y1923550D03*
X767999Y1923050D03*
X774499Y1930050D03*
X768999D03*
X775814Y1975699D03*
X770814Y1971713D03*
X771814Y1975713D03*
X796873Y307571D03*
Y303071D03*
Y298571D03*
Y294071D03*
X784478Y355424D03*
Y359924D03*
X794331Y698353D03*
Y702853D03*
Y707353D03*
Y711853D03*
X799385Y761436D03*
X783196Y760382D03*
Y755882D03*
X802499Y1097566D03*
X798499D03*
X783333Y1157392D03*
Y1161892D03*
X795999Y1509550D03*
Y1504550D03*
Y1518550D03*
Y1514050D03*
X785827Y1561296D03*
Y1565796D03*
X782827Y1569796D03*
X795526Y1909696D03*
X795493Y1913696D03*
X795501Y1917696D03*
X795499Y1922050D03*
X783814Y1967213D03*
Y1971713D03*
X784016Y1975708D03*
X809373Y307571D03*
Y297571D03*
Y292571D03*
X808999Y303050D03*
X806831Y701853D03*
Y706853D03*
X806999Y697050D03*
X806831Y711853D03*
X811499Y1097050D03*
X807499D03*
X807341Y1111216D03*
Y1101216D03*
X806999Y1106050D03*
X807341Y1116216D03*
X809245Y1508722D03*
Y1503722D03*
Y1518722D03*
X808999Y1513550D03*
X807936Y1914865D03*
Y1910365D03*
X807997Y1922865D03*
X808005Y1918865D03*
X839999Y46050D03*
X840499Y55050D03*
X840999Y62550D03*
X841499Y71550D03*
X843499Y82550D03*
X838999Y85050D03*
X837999Y91050D03*
X838499Y107050D03*
Y99550D03*
X839499Y119050D03*
X865499Y39550D03*
X854499D03*
X856499Y71050D03*
X855499Y82050D03*
X845999Y111050D03*
X865499Y125550D03*
X864414Y1940050D03*
X883999Y39050D03*
X881499Y70550D03*
X866999D03*
X876999Y82050D03*
X867499D03*
X886499Y99550D03*
Y104550D03*
X875499Y125550D03*
X866499Y724550D03*
X873499Y1356050D03*
X882700Y1738300D03*
X886900Y1737900D03*
X902999Y22050D03*
X902499Y35050D03*
X905499Y56550D03*
X904999Y61550D03*
X904499Y74050D03*
X904999Y67550D03*
X890459Y100116D03*
X890499Y104550D03*
X903999Y574378D03*
X904814Y1789113D03*
X917499Y21550D03*
X909499D03*
X909999Y35550D03*
X916499Y36050D03*
X928499Y51550D03*
X928999Y56050D03*
X928499Y60550D03*
X928999Y65550D03*
X929999Y32550D03*
X940499Y33050D03*
X945499Y33550D03*
X943499Y48050D03*
Y55050D03*
Y72550D03*
X942999Y61550D03*
Y66550D03*
X943499Y78050D03*
X950100Y1626100D03*
X972000Y1442000D03*
Y1437500D03*
X971700Y1448300D03*
X962500Y1436500D03*
Y1441000D03*
X952800Y1437500D03*
Y1442000D03*
X962200Y1447300D03*
X952500Y1448300D03*
X971500Y1467500D03*
X971700Y1457800D03*
Y1462300D03*
Y1452800D03*
X962000Y1466500D03*
X952300Y1467500D03*
X962200Y1451800D03*
X952500Y1452800D03*
X962200Y1456800D03*
Y1461300D03*
X952500Y1457800D03*
Y1462300D03*
X966000Y1475000D03*
X958800Y1472500D03*
X966000Y1479500D03*
Y1484000D03*
X958800Y1477000D03*
Y1481500D03*
X965700Y1489300D03*
X958500Y1486800D03*
X960200Y1495300D03*
X951500D03*
X960049Y1500300D03*
X951349D03*
X960049Y1504800D03*
X951349D03*
X973500Y1483000D03*
Y1478500D03*
X973200Y1488300D03*
X973500Y1474000D03*
X972549Y1502300D03*
Y1506800D03*
X972700Y1497300D03*
G54D22*
X185999Y250550D03*
X168999Y413050D03*
X188499Y413550D03*
X205938Y72528D03*
X191999Y221550D03*
X203499Y250550D03*
X209499Y412550D03*
X210605Y70692D03*
X210685Y74725D03*
X215138Y72559D03*
X210634Y66863D03*
X210638Y62959D03*
X210738Y82159D03*
Y78459D03*
X210999Y221550D03*
X217999Y250550D03*
X232400Y220700D03*
X232999Y414550D03*
X252499Y415050D03*
X251499Y446050D03*
X231999Y445550D03*
X251999Y462050D03*
X232499Y461550D03*
X271999Y216050D03*
X265999Y245050D03*
X269999Y415050D03*
X272499Y445050D03*
X272999Y461050D03*
X290999Y216050D03*
X283499Y245050D03*
X284499Y415050D03*
X286999Y462050D03*
X292999Y483550D03*
X310499Y216550D03*
X297999Y245050D03*
X303999Y415550D03*
X306100Y462000D03*
X312499Y484050D03*
X337499Y282550D03*
X324999Y414550D03*
X327900Y463200D03*
X333499Y483050D03*
X343999Y190050D03*
X355499Y219050D03*
X337999D03*
X343499Y253550D03*
X354999Y282550D03*
X362999Y190050D03*
X369999Y219050D03*
X362499Y253550D03*
X369499Y282550D03*
X382499Y190550D03*
X381999Y254050D03*
X415999Y518550D03*
X438999Y381550D03*
X435499Y519050D03*
X448999Y255550D03*
X444499Y283050D03*
X463999Y283550D03*
X443499Y354050D03*
X464499Y353050D03*
X458499Y382050D03*
X456499Y518050D03*
X469999Y254550D03*
X481499Y283550D03*
X483499Y353050D03*
X485000Y373200D03*
X484900Y394700D03*
X488999Y254550D03*
X495999Y283550D03*
X502999Y353550D03*
X508499Y255050D03*
X525999D03*
X515499Y284050D03*
X520499Y353550D03*
X509999Y382550D03*
X514499Y546050D03*
X540499Y255050D03*
X536499Y283050D03*
X548100Y362200D03*
X530999Y381550D03*
X535499Y545050D03*
X538999Y562050D03*
X558499Y562550D03*
X579499Y561550D03*
X606499Y584550D03*
X625999Y585050D03*
X646999Y584550D03*
X674999Y601550D03*
X699999Y610050D03*
X721499Y617550D03*
X744999Y626550D03*
X757400Y686300D03*
X777499Y638050D03*
Y664550D03*
X771800Y686600D03*
X785499Y641050D03*
X794999Y664550D03*
X786500Y686100D03*
X798000Y686400D03*
X809700Y686300D03*
X806300Y670600D03*
X841000Y671100D03*
X923761Y85550D03*
X928561Y95181D03*
X928428Y83714D03*
X928508Y87747D03*
X928561Y91481D03*
X928457Y79885D03*
X928461Y75981D03*
X932961Y85581D03*
G54D11*
X17600Y5604D03*
X15499Y328050D03*
Y342550D03*
Y360050D03*
X14799Y751450D03*
X8599Y751650D03*
X17299Y773950D03*
X10999Y774050D03*
X18099Y1343550D03*
X9399Y1347350D03*
X15299Y1723450D03*
X15399Y1708350D03*
X7099Y1717750D03*
X7199Y1731450D03*
X14899Y1736250D03*
X15299Y1753250D03*
X6099Y1753750D03*
X11299Y1850050D03*
X9099Y1881550D03*
X14999Y1940050D03*
X8499Y1979550D03*
X11500Y1987000D03*
X36000Y5604D03*
X23499Y27050D03*
X40999Y27550D03*
X27799Y38450D03*
X40999Y42050D03*
X25799Y64050D03*
X28399Y94950D03*
X34999Y108550D03*
X41399Y134150D03*
X27999Y131050D03*
Y145550D03*
Y163050D03*
X23999Y243550D03*
Y229050D03*
Y261050D03*
X39999Y327550D03*
Y342050D03*
Y359550D03*
X29699Y388484D03*
X29599Y382884D03*
X23399Y373931D03*
Y389679D03*
X23499Y381831D03*
X29999Y398684D03*
X29899Y404384D03*
X23799Y405684D03*
X23499Y397579D03*
X28672Y429356D03*
X29365Y421169D03*
X23399Y429051D03*
X28700Y451900D03*
X28800Y436700D03*
X28700Y445700D03*
X23399Y444799D03*
X23499Y452699D03*
Y436951D03*
X29500Y460800D03*
X23499Y468447D03*
X23399Y476295D03*
Y460547D03*
Y492043D03*
X23499Y484195D03*
X28600Y508500D03*
X38400Y514955D03*
X28664Y499429D03*
X23499Y515691D03*
Y499943D03*
X23399Y507791D03*
X35338Y524746D03*
X26691Y532701D03*
X22800Y539600D03*
X23399Y523539D03*
X23499Y531439D03*
X39999Y576550D03*
X22699Y577950D03*
X22999Y565550D03*
X22978Y588571D03*
X26869Y616861D03*
X23499Y618053D03*
X23999Y609250D03*
X34976Y619250D03*
X30712Y624971D03*
X29999Y640550D03*
X29819Y634951D03*
X23399Y641649D03*
X23799Y625950D03*
X23499Y633801D03*
X30999Y656250D03*
Y650550D03*
X23499Y665297D03*
Y649549D03*
X23725Y657471D03*
X23699Y673150D03*
X23499Y681045D03*
X29999Y694550D03*
X25999Y694870D03*
X23999Y689050D03*
X26399Y750850D03*
X39899Y754850D03*
X39399Y768750D03*
X27199Y764950D03*
X28599Y775450D03*
X26299Y815050D03*
X22500Y853700D03*
X26799Y874550D03*
X26099Y891650D03*
X25699Y916150D03*
X25099Y942150D03*
X23899Y957950D03*
X24799Y992250D03*
X33899Y1005950D03*
X20400Y1048300D03*
X23700Y1354600D03*
X22851Y1374169D03*
X22999Y1366050D03*
X23499Y1381550D03*
X32550Y1392777D03*
X27499Y1387550D03*
X24499Y1389663D03*
X33321Y1414755D03*
X29786Y1414858D03*
X23499Y1421550D03*
X23999Y1413550D03*
X36198Y1446749D03*
X27099Y1444350D03*
X30999Y1438050D03*
X27999Y1430050D03*
X23499Y1445050D03*
X22999Y1437050D03*
X23999Y1429050D03*
X29069Y1459379D03*
X36791Y1460866D03*
X23028Y1468579D03*
X23499Y1460550D03*
X22999Y1453050D03*
X32520Y1485092D03*
X28999Y1478050D03*
X23599Y1476350D03*
X23277Y1484050D03*
X27499Y1495050D03*
X36999Y1494550D03*
X22999Y1500050D03*
X23799Y1508050D03*
X24499Y1492050D03*
X35245Y1522512D03*
X35999Y1514550D03*
X29765Y1515282D03*
X24423Y1527123D03*
X22999Y1515550D03*
X25247Y1546912D03*
X24999Y1569550D03*
X31149Y1568300D03*
X23608Y1572653D03*
X24323Y1559950D03*
X22699Y1594224D03*
X31099Y1595350D03*
X26999Y1610550D03*
X34884Y1615734D03*
X23499Y1618050D03*
Y1610050D03*
Y1602050D03*
X32199Y1633124D03*
X34816Y1630953D03*
X22999Y1626050D03*
X23499Y1634050D03*
X27499Y1657050D03*
X32989Y1648451D03*
X26785Y1642089D03*
X23499Y1657050D03*
X23999Y1649550D03*
X23415Y1641634D03*
X34699Y1663300D03*
X22999Y1665550D03*
X24244Y1681868D03*
X22864Y1673550D03*
X31499Y1849750D03*
X22099Y1836609D03*
X39399Y1864350D03*
X23999Y1857950D03*
X27199Y1874350D03*
X34799Y1890050D03*
X28799Y1919060D03*
X34799Y1946750D03*
X38703Y1946754D03*
X26500Y1987000D03*
X55700Y5900D03*
X50999Y21150D03*
Y47750D03*
X59499Y90550D03*
Y76050D03*
Y108050D03*
X52499Y130550D03*
Y145050D03*
Y162550D03*
X41699Y183250D03*
X41999Y200050D03*
X48499Y243050D03*
Y228550D03*
Y260550D03*
X42999Y275650D03*
X51099Y300050D03*
X52199Y342350D03*
X47543Y578340D03*
X44959Y575756D03*
X42299Y564150D03*
X62055Y561550D03*
X49555Y563550D03*
X61099Y603236D03*
X60076Y595777D03*
X55499Y595650D03*
X52333Y641295D03*
X57800Y634300D03*
X44900Y642800D03*
X47800Y692800D03*
X53210Y701486D03*
X53999Y791000D03*
X47400Y1721700D03*
X42000Y1740100D03*
X47717Y1731337D03*
X47800Y1740500D03*
X60449Y1842550D03*
X52999Y1871550D03*
X57499Y1871050D03*
X45699Y1875550D03*
X44368Y1951450D03*
X44399Y1942250D03*
X42532Y1946783D03*
X53999Y1946650D03*
X50299D03*
X46565Y1946703D03*
X45999Y1971450D03*
X61500Y1987500D03*
X44500Y1987000D03*
X55999Y1982550D03*
X73900Y6200D03*
X65499Y27050D03*
Y41550D03*
Y59050D03*
X77165Y110799D03*
X71015Y123666D03*
X78165Y137116D03*
X75299Y261750D03*
X76099Y414250D03*
X75300Y454100D03*
X67300Y450200D03*
X68899Y445450D03*
X66199Y475184D03*
Y469884D03*
X77499Y469550D03*
X66299Y490784D03*
Y485484D03*
X77999Y493050D03*
X66099Y500950D03*
X77165Y514650D03*
X77499Y502550D03*
X63499Y538550D03*
Y533050D03*
X70800Y540300D03*
X75999Y556640D03*
X72599Y578236D03*
X74499Y662050D03*
X78499Y654050D03*
X81999Y668050D03*
X79299Y794150D03*
X67999Y790400D03*
X76399Y820450D03*
X70100Y818900D03*
X77499Y921550D03*
X77002Y952079D03*
X76711Y948089D03*
X77499Y962152D03*
X72799Y982950D03*
X65799Y994050D03*
X80000Y1090500D03*
X74500Y1097550D03*
X79899Y1104550D03*
X74399Y1111550D03*
X78499Y1273550D03*
X78613Y1282664D03*
X78779Y1302664D03*
Y1312664D03*
X77165Y1327335D03*
X77166Y1353400D03*
X76499Y1507050D03*
Y1498050D03*
Y1512050D03*
Y1503050D03*
X76999Y1528050D03*
Y1519050D03*
X78100Y1688189D03*
X83599Y1744750D03*
X77165Y1759550D03*
X78529Y1788113D03*
X79500Y1987500D03*
X65499Y1982550D03*
X73499D03*
X82999D03*
X90900Y5800D03*
X90899Y14850D03*
X93999Y58550D03*
X92900Y66128D03*
X92999Y86128D03*
Y96128D03*
X89603Y132629D03*
X95814Y136065D03*
X96184Y151065D03*
Y166065D03*
X92899Y231450D03*
X86899Y242750D03*
X93199Y279650D03*
X84899Y289250D03*
X90899Y309550D03*
X94199Y325550D03*
X93499Y337450D03*
X89899Y368350D03*
X95499Y355450D03*
X89999Y396450D03*
X87599Y403950D03*
X95399Y416350D03*
X89099Y426150D03*
X99399Y437450D03*
X96900Y510000D03*
X93200Y510500D03*
X83700Y529500D03*
X88999Y538050D03*
X104502Y530552D03*
X101500Y536500D03*
X93599Y581236D03*
X93100Y571640D03*
X92599Y606236D03*
X92999Y868550D03*
X92499Y876550D03*
X93499Y897152D03*
X93000Y907165D03*
X89469Y935588D03*
X83988Y934028D03*
X89499Y942850D03*
X86700Y982100D03*
X102999Y1188050D03*
X104999Y1231050D03*
X100999Y1231032D03*
X103499Y1305050D03*
X102000Y1341000D03*
X91279Y1340642D03*
X86165Y1339050D03*
X101500Y1352000D03*
X89999Y1348050D03*
X93316Y1351000D03*
X96000Y1369000D03*
X96100Y1384650D03*
X100499Y1479650D03*
X90999Y1628550D03*
Y1624550D03*
X91121Y1632549D03*
X86299Y1632550D03*
X85999Y1628550D03*
Y1624550D03*
X92900Y1678176D03*
X92873Y1708176D03*
X92479Y1718176D03*
X84099Y1737150D03*
X89306Y1746856D03*
X89499Y1753575D03*
X93499Y1759550D03*
X94336Y1773113D03*
X104417Y1791480D03*
X97999Y1815050D03*
X104500Y1813400D03*
X101699Y1983850D03*
X98000Y1987500D03*
X91499Y1983050D03*
X107000Y6000D03*
X112999Y124050D03*
X111790Y132259D03*
X123499Y149050D03*
Y140050D03*
X117500Y162300D03*
X124300Y167800D03*
X114900Y177900D03*
X124999Y246050D03*
X123378Y255944D03*
X109499Y410250D03*
X124899Y409050D03*
X126099Y396150D03*
X111299Y425850D03*
X122499Y427900D03*
X107526Y528996D03*
X108599Y557236D03*
X108900Y587600D03*
X124999Y643050D03*
X112200Y762200D03*
X112000Y773000D03*
X111299Y821050D03*
X112999Y901150D03*
X106749Y934367D03*
X108441Y924705D03*
X106500Y943000D03*
X105300Y960300D03*
X124100Y1047100D03*
X120100Y1053200D03*
X121500Y1083600D03*
X121100Y1075300D03*
X117499Y1079300D03*
X116249Y1102550D03*
X112999Y1103740D03*
X106999Y1114960D03*
X120999Y1188050D03*
X111999D03*
X114999Y1210363D03*
X121657Y1224604D03*
X120999Y1228550D03*
X118999Y1219050D03*
X120499Y1264550D03*
X123938Y1267623D03*
X117149Y1267550D03*
X111499Y1311800D03*
X113000Y1341000D03*
X107228Y1330552D03*
X107500Y1340500D03*
X113500Y1352000D03*
X110499Y1365050D03*
X109999Y1355050D03*
X119507Y1423540D03*
X107328Y1438218D03*
X114499Y1432050D03*
X107999Y1448050D03*
X105099Y1459150D03*
X123999Y1473050D03*
X122199Y1476050D03*
X124999Y1616050D03*
Y1620050D03*
Y1629050D03*
Y1633050D03*
X119999Y1629050D03*
X120100Y1633100D03*
X122499Y1668550D03*
Y1672550D03*
X118999Y1670550D03*
X104999Y1708963D03*
X117249Y1712090D03*
X107499Y1736550D03*
X106999Y1746290D03*
X120299Y1796150D03*
X111499Y1877550D03*
Y1882550D03*
X122999Y1883050D03*
X115999Y1882550D03*
X116499Y1877550D03*
X122999Y1889050D03*
X108499Y1981750D03*
X115000Y1987000D03*
X127999Y157050D03*
X133999Y149050D03*
X142999Y141050D03*
X132999Y141550D03*
X144499Y149050D03*
X131799Y201950D03*
X142688Y218861D03*
X143110Y203861D03*
X133000Y240500D03*
X147099Y245350D03*
X135399Y277050D03*
X130799Y300250D03*
X130099Y326150D03*
X134699Y356050D03*
X139399Y372350D03*
X133499Y445050D03*
X128999Y445550D03*
X130000Y452000D03*
X139200Y484300D03*
X134499Y488050D03*
X138999Y524213D03*
X140000Y587700D03*
X140499Y600550D03*
X143999Y605550D03*
X128725Y636626D03*
X128479Y640589D03*
X141773Y643013D03*
X140499Y626050D03*
Y649350D03*
X134300Y646400D03*
X131099Y700450D03*
X139099Y707150D03*
X141500Y711000D03*
X141234Y1029885D03*
X140864Y1044885D03*
X137100Y1084800D03*
X140800Y1076300D03*
X137900Y1103400D03*
X139100Y1097100D03*
X134500Y1108100D03*
X143200Y1116300D03*
X133200Y1132100D03*
X126400Y1138100D03*
X145900Y1163200D03*
X144399Y1171150D03*
X141499Y1185550D03*
X128400Y1188600D03*
X143899Y1196750D03*
X142499Y1205550D03*
X130999Y1198050D03*
X130699Y1210653D03*
X126499Y1264550D03*
X125999Y1315550D03*
X132999Y1319550D03*
X142667Y1319218D03*
X133475Y1331200D03*
X145999Y1353050D03*
X138000Y1359025D03*
X143199Y1412050D03*
X140799Y1435460D03*
X139815Y1454438D03*
X139235Y1460973D03*
X127898Y1462441D03*
X126562Y1670613D03*
X141500Y1715500D03*
X126599Y1789650D03*
X142144Y1801644D03*
X141101Y1866545D03*
X140999Y1859550D03*
X143490Y1855972D03*
X127499Y1889050D03*
X126999Y1882550D03*
X135999Y1881550D03*
X142499Y1905972D03*
X141499Y1895972D03*
X146899Y1961750D03*
X146000Y1987500D03*
X128500D03*
X157299Y5150D03*
X152999Y141050D03*
X167499Y149550D03*
X163499Y140050D03*
X160999Y149550D03*
X152499D03*
X166800Y240800D03*
X158999Y259800D03*
X152808Y246341D03*
X157740Y273924D03*
X157440Y283924D03*
Y303924D03*
Y313924D03*
X167299Y369350D03*
X150699Y411050D03*
X152499Y395950D03*
X165699Y428050D03*
X153459Y427494D03*
X154101Y445550D03*
X163449Y521650D03*
X154099Y529236D03*
X160932Y549468D03*
X162500Y623400D03*
X161000Y639100D03*
X152400Y643300D03*
X152124Y651868D03*
X159054Y665400D03*
X158885Y679436D03*
Y689436D03*
X158385Y719436D03*
X159500Y814700D03*
X161999Y843550D03*
Y848050D03*
X156499Y846050D03*
X156999Y850050D03*
X158114Y883290D03*
X156499Y886950D03*
X160399Y922850D03*
X153299Y943750D03*
X156499Y985950D03*
X149499Y997650D03*
X162499Y1023550D03*
X158300Y1015000D03*
X163499Y1035050D03*
X159499Y1044579D03*
X165600Y1057428D03*
X168099Y1083550D03*
X164999Y1075550D03*
X159055Y1070400D03*
X159000Y1083000D03*
X167999Y1092850D03*
X167499Y1118550D03*
X167999Y1130550D03*
X157700Y1114948D03*
X157600Y1124948D03*
X163499Y1171650D03*
X151699Y1158550D03*
X151499Y1173050D03*
X150999Y1181150D03*
X149562Y1315987D03*
X167499Y1389050D03*
X156999Y1397750D03*
X166799Y1409350D03*
X157915Y1420460D03*
X163499Y1433350D03*
X165499Y1453550D03*
X150338Y1453958D03*
X152499Y1462940D03*
X166799Y1487450D03*
X157440Y1490460D03*
X159054Y1476200D03*
X157440Y1500460D03*
Y1520460D03*
Y1530460D03*
X165575Y1676975D03*
X157500Y1797400D03*
X158000Y1825400D03*
X157999Y1840972D03*
X167200Y1868000D03*
X159054Y1855050D03*
X163599Y1892050D03*
X168299Y1879850D03*
X159054Y1881800D03*
X159173Y1935972D03*
X159421Y1925972D03*
X148499Y1977250D03*
X163500Y1987500D03*
X189499Y4550D03*
X168499Y65550D03*
X175999Y82428D03*
X169999Y129050D03*
X176499Y140050D03*
X173499Y149050D03*
X177899Y199250D03*
X181299Y267350D03*
X187199Y359050D03*
X181599Y396250D03*
X173100Y483100D03*
X182499Y532550D03*
X168453Y527949D03*
X181999Y624050D03*
Y609550D03*
Y641550D03*
X182599Y688350D03*
X171999Y672450D03*
X170799Y689150D03*
X178899Y765250D03*
X172599Y774250D03*
X172660Y815731D03*
X168499Y846713D03*
X173899Y846550D03*
X174199Y841050D03*
X172099Y877450D03*
X169299Y956350D03*
X171499Y998650D03*
X169299Y1067150D03*
X171599Y1139950D03*
X180400Y1202800D03*
X181700Y1219900D03*
X179800Y1244100D03*
X179500Y1262000D03*
X178200Y1393400D03*
X180599Y1424050D03*
X180000Y1439500D03*
X176599Y1447450D03*
X172299Y1465850D03*
X181500Y1479000D03*
X176299Y1500150D03*
X179999Y1655887D03*
X181900Y1675300D03*
X180701Y1716050D03*
X179701Y1724550D03*
X180000Y1731000D03*
X185999Y1746050D03*
X182299Y1801350D03*
X173899Y1813250D03*
X177599Y1866750D03*
X168499Y1855550D03*
X181099Y1885850D03*
X168699Y1957150D03*
X183999Y1968150D03*
X188199Y1978250D03*
X183000Y1987500D03*
X206999Y5050D03*
X191999Y68050D03*
X201499Y104550D03*
X206899Y171650D03*
X190199Y178650D03*
X197899Y165075D03*
X201199Y266750D03*
X209199Y365050D03*
X209999Y426150D03*
X205300Y508100D03*
X190499Y507513D03*
X193549Y575875D03*
X206499Y623550D03*
Y609050D03*
X207300Y639400D03*
X199199Y659150D03*
X190399Y689050D03*
X209500Y759000D03*
X208799Y766750D03*
X190699Y778350D03*
X197099Y795050D03*
X208299Y805350D03*
X202900Y811900D03*
X198199Y805950D03*
X200000Y818000D03*
X200539Y890300D03*
X198499Y884113D03*
X204699Y929450D03*
X206699Y953050D03*
X203999Y943350D03*
X205999Y978250D03*
X198924Y975975D03*
X206299Y990250D03*
X207299Y1008150D03*
X202100Y1028100D03*
X199499Y1093850D03*
X209900Y1093600D03*
X208199Y1145850D03*
X210199Y1173450D03*
X204199Y1163850D03*
X201600Y1205900D03*
X196499Y1215550D03*
Y1196550D03*
X196399Y1236650D03*
X196499Y1224550D03*
X195499Y1251050D03*
X202199Y1276850D03*
X195499Y1279050D03*
Y1270050D03*
X202899Y1291450D03*
X207699Y1337950D03*
X195500Y1352500D03*
X208049Y1385550D03*
X203199Y1393250D03*
X204699Y1418350D03*
X201000Y1408500D03*
X194200Y1457900D03*
X204999Y1472650D03*
X208999Y1491250D03*
X202399Y1500750D03*
X209200Y1624000D03*
X193500Y1647000D03*
X200600Y1663600D03*
X199900Y1670600D03*
X193499Y1674050D03*
X197600Y1694900D03*
X204400Y1688200D03*
X209901Y1691850D03*
X201801Y1701450D03*
X195001Y1708150D03*
X205200Y1708000D03*
X195500Y1717000D03*
X195000Y1725500D03*
X206900Y1726700D03*
X199699Y1761450D03*
X205199Y1801950D03*
X194049Y1792600D03*
X209999Y1825050D03*
X192100Y1813500D03*
X204399Y1855450D03*
X206999Y1867550D03*
X207199Y1892850D03*
X191599Y1891550D03*
X199599Y1879850D03*
X205499Y1968650D03*
X190199Y1957650D03*
X199600Y1974900D03*
X209699Y1978750D03*
X199000Y1987500D03*
X226499Y5050D03*
X229099Y161350D03*
X213499Y283864D03*
X214063Y318114D03*
X223799Y365350D03*
X213400Y355300D03*
X224998Y357049D03*
X217599Y396450D03*
X218499Y474850D03*
X224299Y494650D03*
X220499Y560050D03*
Y545550D03*
Y577550D03*
X224999Y613450D03*
X219999Y632550D03*
Y647050D03*
X226399Y677550D03*
X212999Y677350D03*
X218800Y668700D03*
X216999Y686550D03*
X213999Y725050D03*
X230849Y726050D03*
X224099Y770250D03*
X228999Y765550D03*
X218224Y765325D03*
X214799Y774750D03*
X227199Y795050D03*
X217300Y816800D03*
X229562Y904113D03*
X215499Y905550D03*
X225299Y957650D03*
X213999Y958650D03*
X217499Y981050D03*
X216999Y967550D03*
X217499Y998550D03*
X217999Y1012050D03*
X215999Y1039550D03*
X216499Y1053050D03*
X221300Y1083238D03*
X214499Y1154250D03*
X223099Y1182750D03*
X212499Y1184550D03*
Y1212550D03*
X221599Y1237250D03*
X220999Y1224350D03*
X222299Y1251850D03*
X229899Y1250550D03*
X211499Y1258050D03*
Y1239050D03*
X216300Y1274800D03*
X211499Y1267050D03*
X219099Y1325950D03*
X226599Y1340250D03*
X213199Y1350050D03*
X227399Y1363050D03*
X217499Y1387450D03*
X230599Y1400250D03*
X217999Y1408850D03*
X227999Y1421550D03*
X226300Y1447800D03*
X230899Y1437350D03*
X212400Y1433700D03*
X213399Y1500300D03*
X212899Y1535550D03*
X230999D03*
X211999Y1568550D03*
X231499Y1575050D03*
X224499D03*
X217999Y1574550D03*
X211999D03*
X218000Y1614300D03*
X228999Y1637550D03*
X211999Y1653550D03*
X230600Y1670500D03*
X213000Y1672500D03*
X216601Y1684350D03*
X226800Y1684200D03*
X220100Y1691700D03*
X212000Y1701300D03*
X222700Y1710100D03*
X222499Y1743850D03*
X221499Y1760950D03*
X220799Y1791550D03*
X215299Y1813950D03*
X224800Y1867000D03*
X228999Y1856050D03*
X212399Y1885850D03*
X213562Y1926113D03*
X220062Y1931113D03*
X227499Y1971050D03*
X221300Y1971200D03*
X225199Y1978750D03*
X216999Y1987550D03*
X241999Y5050D03*
X247499Y37550D03*
X246999Y46550D03*
Y51550D03*
X246499Y42550D03*
X246999Y56050D03*
X247499Y65050D03*
X246999Y69550D03*
Y60550D03*
X246499Y86050D03*
Y80550D03*
X245499Y100550D03*
X244499Y136550D03*
Y122050D03*
X244900Y149100D03*
X249800Y248800D03*
X235399Y263350D03*
X231800Y318414D03*
X233998Y357549D03*
X239400Y357400D03*
X237699Y426050D03*
X244199Y483350D03*
X242099Y511750D03*
X244999Y559550D03*
Y545050D03*
Y577050D03*
X244499Y632050D03*
X246500Y663300D03*
X245000Y647000D03*
X234200Y668300D03*
X252499Y726050D03*
X241600Y765700D03*
X236800Y765800D03*
X245599Y773450D03*
X234299Y773750D03*
X247099Y795050D03*
X233799Y806350D03*
X245399Y823550D03*
X244099Y857450D03*
X252399Y838250D03*
X245199Y878050D03*
X232399Y886550D03*
X252899Y886350D03*
X245399Y907450D03*
X243899Y923650D03*
X242199Y938750D03*
X252499Y948850D03*
X244199Y973250D03*
X232299Y981950D03*
X233499Y966050D03*
X245899Y995250D03*
X233999Y997050D03*
Y1012550D03*
X232499Y1038050D03*
X249499Y1104150D03*
X232599Y1195750D03*
X251999Y1184550D03*
X242199Y1210050D03*
X242599Y1198350D03*
X247899Y1208650D03*
X234299Y1232650D03*
X250900Y1248500D03*
X242900Y1263000D03*
X232799Y1276150D03*
X241399Y1303250D03*
X239099Y1314150D03*
X252399Y1326350D03*
X245999Y1339050D03*
Y1358050D03*
X234300Y1375700D03*
X246499Y1370050D03*
X249800Y1388400D03*
X244999Y1412550D03*
X245499Y1424550D03*
X238899Y1453750D03*
X248000Y1482000D03*
X250199Y1473550D03*
X247500Y1499000D03*
X232650Y1493450D03*
X236999Y1535550D03*
X238300Y1575100D03*
X246200Y1617600D03*
X239400Y1624300D03*
X242999Y1658050D03*
X237400Y1663800D03*
X235499Y1697050D03*
X249199Y1743150D03*
X237999Y1730550D03*
X244999Y1755050D03*
X252199Y1793050D03*
X238699Y1801850D03*
X241199Y1867150D03*
X244700Y1878700D03*
X232314Y1890513D03*
X236225Y1883125D03*
X241255Y1896055D03*
X240964Y1934113D03*
X238999Y1970550D03*
X232999Y1971050D03*
X240900Y1979000D03*
X236500Y1987500D03*
X261499Y4550D03*
X253999Y48050D03*
Y44050D03*
X264999Y55350D03*
X261299Y75950D03*
X258699Y104550D03*
X265299Y96250D03*
X262299Y164050D03*
X262699Y208550D03*
X252935Y319114D03*
X258999Y396650D03*
X266699Y425050D03*
X266199Y472350D03*
X257499Y498050D03*
Y512550D03*
Y530050D03*
X256499Y577050D03*
Y591550D03*
Y609050D03*
X269499Y616550D03*
X257199Y640050D03*
X269499Y631050D03*
Y648550D03*
X268099Y795450D03*
X254699Y807650D03*
X264499Y829050D03*
X264999Y842550D03*
Y858450D03*
X265799Y901850D03*
X256199Y916250D03*
X254899Y929250D03*
X253499Y938050D03*
X269599Y923950D03*
X267199Y935350D03*
X264799Y946850D03*
X263299Y959350D03*
X272999Y981050D03*
Y965550D03*
X256499Y967050D03*
X262499Y995850D03*
X254499Y984550D03*
X258999Y1011550D03*
X269999Y1037050D03*
X253499Y1038550D03*
X269999Y1052550D03*
X253999Y1052050D03*
X272999Y1102850D03*
X262499Y1129150D03*
X255000Y1125700D03*
X260349Y1139200D03*
X256000Y1133000D03*
X272999Y1214150D03*
X261199Y1227950D03*
X264800Y1261300D03*
X254899Y1289950D03*
X264799Y1313850D03*
X265299Y1339650D03*
X263699Y1359550D03*
X265499Y1376950D03*
X258999Y1396950D03*
X270599Y1408550D03*
X259299Y1438750D03*
X268499Y1453550D03*
X265700Y1635100D03*
X258700Y1645100D03*
X270999Y1660550D03*
X253999Y1676550D03*
X273499Y1694050D03*
X255699Y1722550D03*
X256499Y1710050D03*
X263499Y1734550D03*
X270599Y1748950D03*
X259499Y1760650D03*
X270599Y1801450D03*
X253899Y1813250D03*
X261499Y1825050D03*
X255999Y1855950D03*
X270299Y1867250D03*
X254500Y1987500D03*
X272000D03*
X278999Y5050D03*
X292999Y4550D03*
X291999Y94050D03*
X283599Y106250D03*
X274700Y131500D03*
X280999Y120050D03*
Y152050D03*
X294500Y339000D03*
X277799Y338599D03*
X276299Y376050D03*
X289399Y395750D03*
X291599Y446150D03*
X281999Y497550D03*
Y512050D03*
Y529550D03*
X277999Y545350D03*
X280999Y576550D03*
Y591050D03*
Y608550D03*
X293999Y616050D03*
Y630550D03*
Y648050D03*
X292999Y743650D03*
X277039Y740300D03*
X287799Y794850D03*
X275299Y806350D03*
X288899Y820550D03*
X280999Y827550D03*
X283599Y857450D03*
X293899Y843850D03*
X280999Y843050D03*
Y870050D03*
X281499Y883550D03*
X274299Y912950D03*
X287299Y901050D03*
X281099Y943550D03*
X278799Y956150D03*
X290099Y948650D03*
X289399Y963350D03*
X277599Y975250D03*
X288099Y971250D03*
X285399Y982950D03*
X294699Y989550D03*
X287099Y1000150D03*
X274999Y996550D03*
X289699Y1021750D03*
X275099Y1024750D03*
X274999Y1012050D03*
X287099Y1035050D03*
X282999Y1099550D03*
X274900Y1115600D03*
X290699Y1122650D03*
X283499Y1113050D03*
X276299Y1134550D03*
X283299Y1144850D03*
X291399Y1174150D03*
X279799Y1191750D03*
X286599Y1203750D03*
X283799Y1249250D03*
X274299Y1276450D03*
X281099Y1302850D03*
X286799Y1326450D03*
X286499Y1364050D03*
Y1345050D03*
X278799Y1386250D03*
X285499Y1399550D03*
X278000Y1422000D03*
X285499Y1418550D03*
Y1427550D03*
X286600Y1449700D03*
X286700Y1516100D03*
X289999Y1554650D03*
X293700Y1553351D03*
X276039Y1551300D03*
X291400Y1561500D03*
X278499Y1621550D03*
X289000Y1641800D03*
X284300Y1676900D03*
X291099Y1707450D03*
X280499Y1718550D03*
X285499Y1742550D03*
X290699Y1760750D03*
X286599Y1791850D03*
X284299Y1811150D03*
X295299Y1870250D03*
X283999Y1856050D03*
X280689Y1942710D03*
X291499Y1987550D03*
X310499Y5050D03*
X296099Y17100D03*
X305099Y17000D03*
X311400Y17100D03*
X306999Y55450D03*
X311299D03*
X315799Y55350D03*
X306100Y126500D03*
X307199Y205550D03*
X313199Y270350D03*
X313000Y313900D03*
X298800Y333000D03*
X313039Y352350D03*
X299899Y376650D03*
X310999Y396250D03*
X300899Y431850D03*
X298599Y501250D03*
X309399Y513450D03*
X297599Y519350D03*
X307499Y555550D03*
Y541050D03*
X297499Y551050D03*
X296199Y568550D03*
X307499Y573050D03*
X302899Y607950D03*
X307499Y661550D03*
Y647050D03*
X297699Y681850D03*
X307499Y679050D03*
X308899Y705150D03*
X298399Y703450D03*
X296399Y716950D03*
X308999Y716450D03*
X315999Y718950D03*
X298000Y743500D03*
X314499Y754550D03*
X307999Y803150D03*
X307899Y794550D03*
X300199Y835250D03*
X304899Y856150D03*
X313499Y847850D03*
X315199Y869450D03*
X297499Y868550D03*
X302499Y899050D03*
X297499Y884050D03*
X302199Y914650D03*
X315199Y925950D03*
X310699Y943550D03*
X299399Y965950D03*
X298099Y977250D03*
X307999Y970650D03*
X306699Y981250D03*
X304399Y997550D03*
X298399Y1008150D03*
X306399Y1020750D03*
X303699Y1038050D03*
X299999Y1052350D03*
X304699Y1057050D03*
X312299Y1093550D03*
X299499Y1098050D03*
Y1113550D03*
X316499Y1124550D03*
X307999Y1142050D03*
X304499Y1156650D03*
X313499Y1170150D03*
X300699Y1185150D03*
X315408Y1202663D03*
X311999Y1213850D03*
X300699Y1227350D03*
X310299Y1240050D03*
X304699Y1265850D03*
X312499Y1280350D03*
X295399Y1292950D03*
X300499Y1305350D03*
X311500Y1316300D03*
X297899Y1336150D03*
X298099Y1357250D03*
X311900Y1344900D03*
X301699Y1377950D03*
X312900Y1366900D03*
X301699Y1395750D03*
X313600Y1391300D03*
X303499Y1411250D03*
X312100Y1420700D03*
X300899Y1433350D03*
X313600Y1442700D03*
X304699Y1457550D03*
X312800Y1467400D03*
X296599Y1497150D03*
X312000Y1514600D03*
X314999Y1527550D03*
X297800Y1561600D03*
X312999Y1566050D03*
X307000Y1619600D03*
X302399Y1662950D03*
X299999Y1696050D03*
X303999Y1722050D03*
X297099Y1733850D03*
X303499Y1753550D03*
X303999Y1800850D03*
X315499Y1812250D03*
X298999Y1855950D03*
X313599Y1870250D03*
X308099Y1880550D03*
X313599Y1889250D03*
X314099Y1901250D03*
X305999Y1913050D03*
X302499Y1922050D03*
X313499Y1919050D03*
X296858Y1956228D03*
X315999Y1958550D03*
X311500Y1987500D03*
X329999Y5050D03*
X317000Y17300D03*
X332200Y94200D03*
X321799Y173950D03*
X317499Y192950D03*
X331499Y193250D03*
X325499Y249450D03*
X316999Y312576D03*
X321748Y343299D03*
X321900Y364600D03*
X328799Y372350D03*
X336099Y417550D03*
X322099Y426850D03*
X328599Y442250D03*
X329999Y510450D03*
X321999Y533150D03*
X331999Y555050D03*
Y540550D03*
X321999Y550550D03*
X321299Y565250D03*
X320799Y582050D03*
X331999Y572550D03*
X328599Y602450D03*
X328499Y635650D03*
X317999Y627850D03*
X331999Y661050D03*
Y646550D03*
Y678550D03*
X324599Y696150D03*
X330799Y712450D03*
X323249Y749010D03*
X324959Y766750D03*
X318999Y814350D03*
X325599Y823950D03*
X330299Y871850D03*
X323799Y859850D03*
X321099Y899650D03*
X323099Y885050D03*
X322099Y913650D03*
X331099Y923650D03*
X328099Y937250D03*
X323499Y956950D03*
X329799Y970650D03*
X333099Y983450D03*
X320999Y997250D03*
X331299Y1017150D03*
X321299Y1012450D03*
Y1024750D03*
X331599Y1028750D03*
X329599Y1040750D03*
X318299Y1038750D03*
X329599Y1057050D03*
X319999Y1066950D03*
X317699Y1054650D03*
X329299Y1098550D03*
X326599Y1112350D03*
X332999Y1123050D03*
X323999Y1153250D03*
X332999Y1138550D03*
X317999Y1137550D03*
X329799Y1182750D03*
X328999Y1200550D03*
X326649Y1227850D03*
Y1218850D03*
X327999Y1255050D03*
X333349Y1270500D03*
Y1288900D03*
Y1307000D03*
Y1332800D03*
Y1363500D03*
Y1393100D03*
Y1429500D03*
Y1481900D03*
X332500Y1519700D03*
X324000Y1562500D03*
X323999Y1577250D03*
X337199Y1636350D03*
X320299Y1642950D03*
X316799Y1657450D03*
X335767Y1662735D03*
X318499Y1675550D03*
X334399Y1691650D03*
X329999Y1716950D03*
X320999Y1706050D03*
X321999Y1733050D03*
X321499Y1772550D03*
X327299Y1791850D03*
X322299Y1802150D03*
X337499Y1855950D03*
X316999D03*
X336799Y1869950D03*
X326399Y1876250D03*
X336799Y1888950D03*
X326899Y1907250D03*
X326399Y1895250D03*
X336799Y1897950D03*
X335799Y1916450D03*
X325221Y1927272D03*
X329999Y1952273D03*
X326799Y1977050D03*
X327100Y1966472D03*
X329999Y1987550D03*
X345499Y5050D03*
X343499Y60150D03*
X357503Y77043D03*
X354099Y175350D03*
X343399Y161350D03*
X343799Y204550D03*
X355999Y242750D03*
X347699Y269050D03*
X347399Y301950D03*
X339399Y358050D03*
X357999Y359050D03*
X354099Y373050D03*
X338399Y395650D03*
X338899Y433850D03*
X354699Y426650D03*
X356399Y451750D03*
X351399Y470750D03*
X340799Y512050D03*
X358399Y498650D03*
X341399Y535850D03*
X357399Y521250D03*
Y530550D03*
X341399Y558950D03*
X357399Y543850D03*
X357999Y559450D03*
X340299Y586550D03*
X342199Y613050D03*
X342099Y646350D03*
X341899Y664950D03*
X342599Y678850D03*
X345399Y698950D03*
X357699Y707750D03*
X341399Y715050D03*
X355999Y752850D03*
X353999Y787750D03*
X347699Y773450D03*
X338099Y811650D03*
X338599Y821650D03*
Y840450D03*
X340099Y887350D03*
X338399Y901050D03*
X340099Y910350D03*
X340399Y931250D03*
X340099Y952850D03*
X339599Y1081550D03*
X344399Y1338150D03*
X343599Y1360050D03*
X344099Y1393750D03*
Y1421150D03*
Y1449550D03*
X351899Y1570850D03*
X344500Y1583600D03*
X350600Y1610900D03*
X349099Y1634550D03*
X351099Y1691150D03*
X352000Y1700400D03*
X343899Y1752650D03*
X357999Y1796050D03*
X355699Y1810750D03*
X351999Y1855450D03*
X348999Y1879050D03*
X349499Y1910050D03*
X348999Y1898050D03*
X347999Y1925550D03*
X348499Y1956550D03*
X347999Y1944550D03*
X347699Y1972250D03*
X345499Y1987550D03*
X364999Y4550D03*
X374499Y77550D03*
X363999Y136050D03*
Y121550D03*
Y153550D03*
X359399Y307250D03*
X368299Y386350D03*
X359399Y576050D03*
Y599650D03*
X360399Y615550D03*
X359699Y627550D03*
X358899Y657150D03*
X359399Y669450D03*
X359199Y690650D03*
X377499Y1182050D03*
Y1210050D03*
Y1201050D03*
X376499Y1236550D03*
Y1255550D03*
Y1264550D03*
X376599Y1293950D03*
X375599Y1323350D03*
X374499Y1347550D03*
Y1375550D03*
Y1366550D03*
X373499Y1402050D03*
Y1421050D03*
X376299Y1437650D03*
X373499Y1430050D03*
X373099Y1456550D03*
X374799Y1491250D03*
X374099Y1554550D03*
X376099Y1572850D03*
X375099Y1608250D03*
X377700Y1629000D03*
X374999Y1656750D03*
X377099Y1696350D03*
X359499Y1736850D03*
X376799Y1734050D03*
X376499Y1775550D03*
X369499Y1855950D03*
X359999Y1878550D03*
X369799Y1880050D03*
X359999Y1897550D03*
Y1906550D03*
X369999Y1901950D03*
X358999Y1925050D03*
X369199Y1919750D03*
X367299Y1956950D03*
X367999Y1940250D03*
X367299Y1972950D03*
X364999Y1987050D03*
X382499Y5050D03*
X395999Y5550D03*
X398799Y36152D03*
X381999Y50150D03*
X382339Y41610D03*
X389599Y90950D03*
X385999Y78050D03*
X380599Y103550D03*
X381299Y136750D03*
X400499Y134050D03*
Y119550D03*
Y151550D03*
X389299Y161650D03*
X387599Y220150D03*
X385999Y207250D03*
X382999Y276650D03*
X386899Y299250D03*
X383299Y310250D03*
X386599Y348450D03*
X394899Y357750D03*
X380599Y381050D03*
X380099Y1709650D03*
X393499Y1759550D03*
X393999Y1784550D03*
X387899Y1802850D03*
X391499Y1855950D03*
X389499Y1885050D03*
Y1913050D03*
Y1904050D03*
X388499Y1932950D03*
Y1950550D03*
X385099Y1975950D03*
X399299Y1976750D03*
X388499Y1959550D03*
X382499Y1987550D03*
X413499Y6050D03*
X416999Y25050D03*
X417499Y46550D03*
X416999Y63550D03*
X417499Y79050D03*
Y93550D03*
X401499Y80550D03*
X417499Y108050D03*
Y125550D03*
X416999Y145050D03*
Y164050D03*
X417999Y185050D03*
X412999Y275550D03*
Y307550D03*
Y290050D03*
X422199Y363350D03*
X420199Y391350D03*
X415099Y422550D03*
X410799Y431150D03*
X419599Y458550D03*
X420199Y638550D03*
X418799Y877050D03*
Y896050D03*
X409499Y1102550D03*
X419999Y1115550D03*
X415499Y1161550D03*
X416099Y1183550D03*
X415499Y1176050D03*
X419499Y1234050D03*
Y1219550D03*
X420099Y1241550D03*
X416699Y1342650D03*
X416199Y1367550D03*
X414799Y1532350D03*
X418299Y1561250D03*
X415999Y1603250D03*
X416199Y1625250D03*
X414799Y1653750D03*
X414399Y1678350D03*
X414499Y1707250D03*
X410757Y1772872D03*
X417799Y1790850D03*
X414499Y1810450D03*
X406999Y1855950D03*
X421399Y1888050D03*
X406499Y1893050D03*
Y1874050D03*
X421399Y1907050D03*
X406999Y1905050D03*
X420399Y1934550D03*
X421399Y1916050D03*
X405499Y1920550D03*
X420399Y1953550D03*
X405999Y1951550D03*
X405499Y1939550D03*
X420399Y1962550D03*
X420799Y1977250D03*
X420500Y1987000D03*
X403500D03*
X432999Y6050D03*
X436499Y31350D03*
Y50350D03*
X437499Y71350D03*
X441799Y102450D03*
Y121450D03*
X442799Y142450D03*
X430499Y217050D03*
X423799Y259750D03*
X437499Y275050D03*
Y307050D03*
Y289550D03*
X422499Y348150D03*
X426599Y415350D03*
X443199Y440850D03*
X440099Y459250D03*
X431099Y479350D03*
X430099Y551450D03*
X427999Y580050D03*
Y565550D03*
Y597550D03*
X427499Y624550D03*
X437299Y744650D03*
X435299Y763150D03*
X424999Y766550D03*
X435299Y777650D03*
X422999Y785050D03*
X434799Y814650D03*
X435299Y795150D03*
X422999Y799550D03*
X434799Y833650D03*
X422999Y817050D03*
X422499Y855550D03*
Y836550D03*
X442599Y905650D03*
Y924650D03*
X423299Y994050D03*
Y1013050D03*
X424299Y1034050D03*
X432599Y1064550D03*
X433599Y1085550D03*
X428999Y1102550D03*
X439499Y1115550D03*
X436999Y1128050D03*
X437599Y1150050D03*
X436999Y1142550D03*
X443199Y1224250D03*
Y1238750D03*
X424999Y1278550D03*
Y1259550D03*
X425499Y1290550D03*
X428499Y1325350D03*
X434499Y1360250D03*
X422299Y1394950D03*
X441499Y1399550D03*
X426799Y1416050D03*
X441499Y1414050D03*
X423299Y1430350D03*
X425799Y1447950D03*
X441499Y1431550D03*
X427099Y1469150D03*
X424299Y1541350D03*
X439599Y1552150D03*
X434500Y1579500D03*
X432499Y1617550D03*
X431999Y1605550D03*
X425499Y1635050D03*
X432400Y1680100D03*
X427499Y1662050D03*
X428600Y1691200D03*
X435300Y1715300D03*
X429499Y1748050D03*
X441499Y1758050D03*
X436799Y1772550D03*
X422999Y1778550D03*
X426499Y1855450D03*
X434299Y1876050D03*
Y1904050D03*
Y1895050D03*
X433299Y1922550D03*
Y1950550D03*
Y1941550D03*
X436299Y1977250D03*
X438999Y1987550D03*
X448499Y6050D03*
X445799Y165650D03*
Y184650D03*
X446799Y205650D03*
X449999Y217050D03*
X450300Y404200D03*
X453999Y417550D03*
X454999Y438550D03*
X454499Y472550D03*
Y458050D03*
Y490050D03*
X453999Y509550D03*
X452499Y579550D03*
Y565050D03*
Y597050D03*
X463999Y659550D03*
X450399Y672750D03*
X444799Y687350D03*
X463999Y674050D03*
Y691550D03*
X451099Y711650D03*
X452099Y762450D03*
Y781450D03*
X453399Y807950D03*
Y826950D03*
X462999Y865050D03*
Y884050D03*
X464499Y896050D03*
X462499Y914550D03*
Y929050D03*
X443599Y945650D03*
X462499Y946550D03*
X461999Y966050D03*
Y985050D03*
X462499Y1043850D03*
Y1062850D03*
X463499Y1083850D03*
X463999Y1102050D03*
X444499Y1102550D03*
X454999Y1115550D03*
X453499Y1140550D03*
X454499Y1161550D03*
X443799Y1246250D03*
Y1274250D03*
Y1265250D03*
X448099Y1341250D03*
X444899Y1377950D03*
X464199Y1401450D03*
X459999Y1424050D03*
X456399Y1445950D03*
X459699Y1468050D03*
X445099Y1464250D03*
X444299Y1532650D03*
X461399Y1541650D03*
X452199Y1550650D03*
X449199Y1579050D03*
X443799Y1612250D03*
X460199Y1632850D03*
X449599Y1656950D03*
X448399Y1699450D03*
X447699Y1682850D03*
X458499Y1742050D03*
X463999Y1772050D03*
X445499Y1792550D03*
X448099Y1809450D03*
X443999Y1855950D03*
X460299Y1892350D03*
X446999Y1880050D03*
X460299Y1911350D03*
X446999Y1908050D03*
Y1899050D03*
X460299Y1920350D03*
X445999Y1926550D03*
X459299Y1938850D03*
X445999Y1954550D03*
Y1945550D03*
X459299Y1966850D03*
Y1957850D03*
X455799Y1976750D03*
X456500Y1987500D03*
X467999Y5550D03*
X485499Y6050D03*
X465799Y24750D03*
Y43750D03*
X466799Y64750D03*
X470399Y84550D03*
Y103550D03*
X471399Y124550D03*
X473099Y141050D03*
X483599Y179350D03*
X473099Y160050D03*
X474099Y181050D03*
X472999Y214550D03*
X466399Y304950D03*
X479299Y297250D03*
X468799Y414250D03*
X472499Y458050D03*
X471499Y493950D03*
X485299Y534550D03*
X479999Y581050D03*
Y566550D03*
Y598550D03*
X472999Y736550D03*
X467699Y772750D03*
X468699Y788350D03*
X479599Y847550D03*
X475699Y880450D03*
X483499Y1064850D03*
X484499Y1085850D03*
X481499Y1102550D03*
X474499Y1115050D03*
X473099Y1144550D03*
X474099Y1165550D03*
X465499Y1265550D03*
Y1284550D03*
Y1293550D03*
X468999Y1323950D03*
X473999Y1342450D03*
X468699Y1362850D03*
X485599Y1367550D03*
X466699Y1378150D03*
X481499Y1402550D03*
Y1417050D03*
X482599Y1449950D03*
X478299Y1464850D03*
X466999Y1530650D03*
X474299Y1544750D03*
X472299Y1572050D03*
X484200Y1579900D03*
X465999Y1603450D03*
X472499Y1611550D03*
X484999Y1636550D03*
X472499Y1620550D03*
X483599Y1662550D03*
X467999Y1668050D03*
X485599Y1694850D03*
X467999Y1687050D03*
Y1696050D03*
X468499Y1712550D03*
X480999Y1756050D03*
X484999Y1779050D03*
X472699Y1792150D03*
X481299Y1811150D03*
X480499Y1855450D03*
X464999D03*
X476199Y1877450D03*
Y1905450D03*
Y1896450D03*
X475199Y1923950D03*
Y1951950D03*
Y1942950D03*
X473299Y1977250D03*
X476000Y1987000D03*
X498999Y6050D03*
X499999Y25550D03*
X500499Y47050D03*
X499999Y64050D03*
X500499Y79550D03*
Y94050D03*
Y108550D03*
Y126050D03*
X499999Y145550D03*
Y164550D03*
X504199Y193250D03*
X502899Y217150D03*
X490999Y412550D03*
X503699Y419250D03*
X490999Y427050D03*
Y444550D03*
X498399Y470050D03*
X490499Y464050D03*
Y483050D03*
X491499Y504050D03*
X504499Y580550D03*
Y566050D03*
Y598050D03*
X488499Y659050D03*
Y673550D03*
Y691050D03*
X506599Y711650D03*
X487299Y716950D03*
X490299Y734550D03*
X489599Y752450D03*
X495999Y795050D03*
X493999Y813550D03*
Y828050D03*
Y845550D03*
X493499Y865050D03*
Y884050D03*
X485799Y920050D03*
Y901050D03*
X486799Y941050D03*
X493099Y996350D03*
X494099Y1017350D03*
X501499Y1102550D03*
X491999Y1115550D03*
X504399Y1132250D03*
X505399Y1153250D03*
X486499Y1210550D03*
Y1196050D03*
X506599Y1202350D03*
Y1216850D03*
X487099Y1218050D03*
X498299Y1323350D03*
X499199Y1350550D03*
X498899Y1386450D03*
Y1408350D03*
X500899Y1434350D03*
X505899Y1466250D03*
X488299Y1531050D03*
X499699Y1538950D03*
X502199Y1566250D03*
X487099Y1606250D03*
X501399Y1634550D03*
X502899Y1709650D03*
X496999Y1799550D03*
X499999Y1854950D03*
X505799Y1893050D03*
X492999Y1878050D03*
X505799Y1912050D03*
X493499Y1909050D03*
X492999Y1897050D03*
X505799Y1921050D03*
X491999Y1924550D03*
X504799Y1939550D03*
X492499Y1955550D03*
X491999Y1943550D03*
X504799Y1967550D03*
Y1958550D03*
X493799Y1977250D03*
X492500Y1987500D03*
X516499Y6550D03*
X522899Y45350D03*
Y64350D03*
X523899Y85350D03*
X520299Y122450D03*
Y141450D03*
X521299Y162450D03*
X516899Y306950D03*
X518999Y416550D03*
X511299Y449150D03*
X519499Y471550D03*
Y489050D03*
X508699Y498950D03*
X518999Y508550D03*
X509999Y640550D03*
Y655050D03*
Y672550D03*
X527499Y747150D03*
X525499Y772450D03*
X511199Y782050D03*
X512899Y823550D03*
X526499Y851150D03*
X512899Y842550D03*
X510899Y868150D03*
X522499Y876050D03*
X521999Y895550D03*
X506899Y919950D03*
Y900950D03*
X521999Y914550D03*
X516499Y957050D03*
X514499Y975550D03*
Y990050D03*
Y1007550D03*
X513999Y1046050D03*
Y1027050D03*
X518999Y1103050D03*
X511999Y1115550D03*
X527499Y1181550D03*
X527999Y1212550D03*
X527499Y1200550D03*
X507199Y1224350D03*
X525999Y1231050D03*
X507199Y1252350D03*
Y1243350D03*
X525999Y1245550D03*
X527499Y1278150D03*
X525999Y1263050D03*
X518499Y1346950D03*
X523499Y1360050D03*
X508599Y1370550D03*
X523499Y1379050D03*
X523999Y1391050D03*
X516999Y1418050D03*
Y1437050D03*
X517499Y1449050D03*
X518899Y1530150D03*
X510100Y1579800D03*
X508199Y1610450D03*
X518499Y1643950D03*
X509199Y1660550D03*
X507399Y1683350D03*
X522300Y1739200D03*
X508200Y1758200D03*
X515499Y1779050D03*
X526499Y1801150D03*
X514199Y1815750D03*
X517499Y1855450D03*
X519399Y1876750D03*
Y1904750D03*
Y1895750D03*
X518399Y1923250D03*
Y1951250D03*
Y1942250D03*
X509299Y1977250D03*
X511999Y1987550D03*
X535999Y6550D03*
X541499Y25050D03*
X541999Y46550D03*
X541499Y63550D03*
X541999Y79050D03*
Y93550D03*
Y108050D03*
Y125550D03*
X541499Y145050D03*
Y164050D03*
X528799Y199950D03*
X542499Y185050D03*
X533499Y217550D03*
X544799Y293950D03*
X540099Y306550D03*
X538799Y445050D03*
X539799Y466050D03*
X539299Y485550D03*
X534499Y640050D03*
Y654550D03*
Y672050D03*
X547999Y728550D03*
Y743050D03*
Y760550D03*
X547499Y780050D03*
X534499Y805950D03*
X547499Y799050D03*
X541399Y854450D03*
Y873450D03*
X539299Y935850D03*
X540299Y956850D03*
X540899Y981450D03*
Y1000450D03*
X541899Y1021450D03*
X534599Y1048550D03*
X535599Y1069550D03*
X538499Y1103050D03*
X548999Y1116050D03*
X529499D03*
X546499Y1180750D03*
Y1195250D03*
X547099Y1202750D03*
Y1230750D03*
Y1221750D03*
X548799Y1252850D03*
Y1267350D03*
X530499Y1297050D03*
X545099Y1355250D03*
X540399Y1382150D03*
X538799Y1409750D03*
X536799Y1436350D03*
X528499Y1460250D03*
X546099Y1467550D03*
X538999Y1528350D03*
X529799Y1555050D03*
X533800Y1575500D03*
X529499Y1616550D03*
X528999Y1604550D03*
X532499Y1635550D03*
X532599Y1655650D03*
X532499Y1669550D03*
Y1688550D03*
X532999Y1700550D03*
X538299Y1721050D03*
X532499Y1763050D03*
X539499Y1788150D03*
X531799Y1818450D03*
X538999Y1855950D03*
X547999Y1892350D03*
X533499Y1884050D03*
X547999Y1911350D03*
X533499Y1912050D03*
Y1903050D03*
X547999Y1920350D03*
X532499Y1930550D03*
X546999Y1938850D03*
X532499Y1949550D03*
X546999Y1966850D03*
Y1957850D03*
X546299Y1977250D03*
X528799Y1976750D03*
X532499Y1958550D03*
X531500Y1987500D03*
X551499Y6550D03*
X568099Y72550D03*
Y91550D03*
X569099Y112550D03*
X562799Y127750D03*
Y146750D03*
X563799Y167750D03*
X565999Y199950D03*
X568499Y217550D03*
X552999D03*
X555999Y412550D03*
X556499Y467550D03*
Y485050D03*
X555999Y504550D03*
X565699Y710650D03*
X549999Y710050D03*
X562999Y898050D03*
X560999Y916550D03*
Y931050D03*
Y948550D03*
X560499Y968050D03*
Y987050D03*
X560999Y999050D03*
X558999Y1017550D03*
Y1032050D03*
X558499Y1069050D03*
X558999Y1049550D03*
X558499Y1088050D03*
X568499Y1101550D03*
X553999Y1103050D03*
X564499Y1116050D03*
X567999Y1187550D03*
Y1215550D03*
Y1206550D03*
X565999Y1234050D03*
Y1248550D03*
X566399Y1273850D03*
X549399Y1274850D03*
X561099Y1301050D03*
X549399Y1293850D03*
Y1302850D03*
X555699Y1322950D03*
X559099Y1343250D03*
X557499Y1424050D03*
Y1443050D03*
Y1452050D03*
X567999Y1549950D03*
X552199Y1576650D03*
X552099Y1601950D03*
X569499Y1610550D03*
X553399Y1624550D03*
X569499Y1619550D03*
X554199Y1651950D03*
X555199Y1674750D03*
X555399Y1689350D03*
X555899Y1706750D03*
X556199Y1727050D03*
X560399Y1792550D03*
X555500Y1802700D03*
X554499Y1855950D03*
X562599Y1893450D03*
Y1874450D03*
Y1902450D03*
X561599Y1920950D03*
Y1948950D03*
Y1939950D03*
X570299Y1976250D03*
X568999Y1987050D03*
X553499D03*
X570999Y6050D03*
X588499Y6550D03*
X587999Y25050D03*
X588499Y46550D03*
X587999Y63550D03*
X588499Y125550D03*
X587999Y145050D03*
Y164050D03*
X588999Y185050D03*
X587999Y217050D03*
X572999Y255050D03*
Y269550D03*
Y287050D03*
X572499Y306550D03*
Y325550D03*
X573499Y346550D03*
X579899Y375750D03*
X577399Y420050D03*
X578399Y441050D03*
X577899Y460550D03*
X576099Y481850D03*
X577099Y502850D03*
X576599Y522350D03*
X573499Y658550D03*
Y673050D03*
Y690550D03*
X586299Y711250D03*
X577999Y732050D03*
X575999Y750550D03*
Y765050D03*
Y782550D03*
X575499Y802050D03*
Y821050D03*
X576499Y842050D03*
X578299Y895650D03*
Y914650D03*
X583299Y961450D03*
X570899Y946850D03*
X583299Y980450D03*
X570899Y965850D03*
X571899Y986850D03*
X573499Y1036550D03*
Y1055550D03*
X574499Y1076550D03*
X588499Y1101550D03*
X578999Y1114550D03*
X582699Y1233250D03*
X583299Y1255250D03*
X582699Y1247750D03*
X583299Y1274250D03*
X579299Y1300750D03*
X583299Y1283250D03*
X581999Y1370150D03*
X580999Y1412750D03*
X575699Y1438950D03*
X582999Y1461250D03*
X590599Y1483450D03*
X582299Y1534150D03*
X588099Y1572050D03*
X573400Y1577600D03*
X588000Y1604000D03*
X590799Y1627850D03*
X580799Y1646150D03*
X572999Y1675550D03*
X590599Y1694450D03*
X572999Y1694550D03*
Y1703550D03*
X580299Y1722550D03*
X582599Y1740050D03*
X573999Y1855450D03*
X588899Y1882350D03*
X575999Y1888050D03*
X588899Y1910350D03*
Y1901350D03*
X575999Y1907050D03*
X587899Y1928850D03*
X576499Y1919050D03*
X574999Y1934550D03*
X587899Y1956850D03*
Y1947850D03*
X574999Y1953550D03*
X585799Y1976250D03*
X575499Y1965550D03*
X588499Y1986550D03*
X608499Y6550D03*
X603999Y35350D03*
Y54350D03*
X604999Y75350D03*
X603999Y133750D03*
Y152750D03*
X604999Y173750D03*
X605499Y217550D03*
X599299Y344650D03*
X600299Y365650D03*
X599799Y385150D03*
X607399Y380250D03*
X592999Y407550D03*
Y422050D03*
Y439550D03*
X592499Y459050D03*
Y478050D03*
X593499Y499050D03*
X595999Y624050D03*
Y609550D03*
Y641550D03*
X605299Y661750D03*
X609499Y708050D03*
X597999Y690050D03*
X607499Y726550D03*
Y741050D03*
Y758550D03*
X606999Y778050D03*
Y797050D03*
X603499Y904050D03*
X601499Y922550D03*
Y937050D03*
Y954550D03*
X600999Y1002050D03*
X611399Y1026650D03*
X598999Y1020550D03*
X611399Y1045650D03*
X598999Y1035050D03*
X612399Y1066650D03*
X598999Y1052550D03*
X598499Y1072050D03*
X605999Y1102050D03*
X598499Y1091050D03*
X598999Y1114550D03*
X603899Y1157850D03*
X597599Y1196050D03*
X596599Y1215050D03*
X600899Y1238650D03*
X598499Y1280550D03*
Y1261550D03*
X598999Y1292550D03*
X608899Y1305050D03*
X605599Y1326350D03*
X606199Y1338250D03*
X599499Y1351550D03*
X599999Y1382550D03*
X599499Y1370550D03*
X604899Y1407750D03*
X601299Y1447650D03*
X610899Y1496750D03*
X599799Y1544650D03*
X611900Y1577900D03*
X612499Y1615550D03*
X611999Y1603550D03*
X600599Y1645450D03*
X593399Y1668850D03*
X609499Y1675050D03*
Y1692050D03*
X607599Y1716450D03*
X606999Y1745550D03*
X593299Y1760950D03*
X608599Y1810750D03*
X595199Y1820910D03*
X611999Y1855950D03*
X591499D03*
X602799Y1887350D03*
Y1906350D03*
X601799Y1933850D03*
X602799Y1915350D03*
X601799Y1952850D03*
Y1961850D03*
X605299Y1975750D03*
X605999Y1987050D03*
X625999Y7050D03*
X624499Y23050D03*
X624999Y44550D03*
X624499Y61550D03*
X624999Y123550D03*
X624499Y143050D03*
Y162050D03*
X625499Y183050D03*
X623899Y202550D03*
X625499Y217550D03*
X627999Y262550D03*
Y248050D03*
Y280050D03*
X627499Y299550D03*
X628200Y320000D03*
X628499Y339550D03*
X632399Y358750D03*
X620999Y411550D03*
X621999Y432550D03*
X621499Y452050D03*
Y466550D03*
Y484050D03*
X613700Y504600D03*
X620499Y623550D03*
Y609050D03*
X631999Y639650D03*
X622999Y672050D03*
Y689550D03*
X629099Y714050D03*
X633499Y750150D03*
X621499Y767150D03*
X621999Y835050D03*
X612999Y854550D03*
X629499Y853050D03*
Y868550D03*
X613499Y868050D03*
X616699Y948250D03*
Y967250D03*
X617699Y988250D03*
X631999Y1001550D03*
X629999Y1020050D03*
Y1034550D03*
Y1052050D03*
X629499Y1071550D03*
Y1090550D03*
X616499Y1115050D03*
X627699Y1143550D03*
X628699Y1164550D03*
X626199Y1183450D03*
X630499Y1243950D03*
X617599Y1246250D03*
X618199Y1268250D03*
X617599Y1260750D03*
X618199Y1296250D03*
Y1287250D03*
X631799Y1322650D03*
X617899Y1360850D03*
X632499Y1347950D03*
X625499Y1383450D03*
X627499Y1406050D03*
X626799Y1432350D03*
X625199Y1489150D03*
X617699Y1530350D03*
X623499Y1564050D03*
X633499Y1615450D03*
X628499Y1636650D03*
X627299Y1659550D03*
X625499Y1725050D03*
X619499Y1803150D03*
X627273Y1793905D03*
X626999Y1800050D03*
X632799Y1820450D03*
X627494Y1829068D03*
X627499Y1855950D03*
X630699Y1872750D03*
Y1891750D03*
Y1900750D03*
X616499Y1913050D03*
Y1894050D03*
X629699Y1919250D03*
X616499Y1922050D03*
X629699Y1947250D03*
Y1938250D03*
X615499Y1940550D03*
X622799Y1976250D03*
X615499Y1959550D03*
Y1968550D03*
X626999Y1987050D03*
X645499Y7050D03*
X651799Y40650D03*
Y59650D03*
X652799Y80650D03*
X649899Y138350D03*
Y157350D03*
X650899Y178350D03*
X642999Y218050D03*
X653999Y286550D03*
X635399Y376250D03*
X643599Y395950D03*
X644599Y416950D03*
X644099Y450950D03*
Y436450D03*
X642499Y525750D03*
X643499Y546750D03*
X642999Y566250D03*
X640599Y604650D03*
X645099Y639150D03*
X647499Y657050D03*
Y671550D03*
X648999Y702350D03*
X647499Y689050D03*
X651999Y718350D03*
X647399Y742150D03*
X653099Y803350D03*
X645799Y816650D03*
X641599Y843250D03*
Y862250D03*
X642599Y883250D03*
X639499Y952150D03*
Y971150D03*
X633999Y1103050D03*
X641799Y1137650D03*
X650299Y1153150D03*
X651299Y1174150D03*
X650599Y1182050D03*
X651599Y1203050D03*
X638999Y1267550D03*
Y1286550D03*
Y1295550D03*
X654499Y1354050D03*
Y1373050D03*
X652999Y1403550D03*
Y1418050D03*
Y1435550D03*
X636799Y1461250D03*
X643099Y1541350D03*
X652399Y1575850D03*
X639200Y1576200D03*
X635500Y1603900D03*
X652499Y1618550D03*
Y1609550D03*
X649399Y1644950D03*
X635099Y1691150D03*
X642499Y1709050D03*
X650399Y1771250D03*
X642400Y1800100D03*
X640999Y1815550D03*
X644049Y1810834D03*
X645099Y1877550D03*
X645399Y1906150D03*
X646799Y1926450D03*
X644999Y1934050D03*
Y1953050D03*
X643799Y1976250D03*
X645499Y1965050D03*
X642499Y1987050D03*
X660999Y7050D03*
X674999Y20550D03*
X675499Y42050D03*
Y74550D03*
X674999Y59050D03*
X675499Y89050D03*
Y103550D03*
Y121050D03*
X674999Y140550D03*
Y159550D03*
X675999Y180550D03*
X662499Y218050D03*
X656499Y307050D03*
Y324550D03*
X655999Y344050D03*
X659899Y363250D03*
X666999Y476550D03*
Y491050D03*
Y508550D03*
X666499Y528050D03*
Y547050D03*
X667499Y568050D03*
X665999Y623550D03*
X673999Y645150D03*
X665499Y766550D03*
X664999Y786050D03*
Y805050D03*
X665999Y826050D03*
X663999Y844550D03*
Y876550D03*
Y859050D03*
X663499Y896050D03*
Y915050D03*
X664499Y936050D03*
X658999Y959050D03*
X656999Y977550D03*
Y992050D03*
X673999Y1017550D03*
X656999Y1009550D03*
X673999Y1036550D03*
X656499Y1029050D03*
X674699Y1061450D03*
X656499Y1048050D03*
X674699Y1080450D03*
X669499Y1116550D03*
X674999Y1134950D03*
X667199Y1152850D03*
X668199Y1173850D03*
X670199Y1192750D03*
X671199Y1213750D03*
X668699Y1227650D03*
X657099Y1272850D03*
X657799Y1288450D03*
X672999Y1303450D03*
X656399Y1307050D03*
X671999Y1324950D03*
X665699Y1337250D03*
X654999Y1385050D03*
X659699Y1445950D03*
X665699Y1462250D03*
X656099Y1479550D03*
X672399Y1508750D03*
X673699Y1535350D03*
X662099Y1549650D03*
X670699Y1603150D03*
X671399Y1625350D03*
X657099Y1668850D03*
X674999Y1676550D03*
X656499Y1697050D03*
X675499Y1738050D03*
X665399Y1752350D03*
X675499Y1757050D03*
X675999Y1769050D03*
X659159Y1792278D03*
X659549Y1815384D03*
Y1810634D03*
X667999Y1870950D03*
X669399Y1855350D03*
X674899Y1892350D03*
X661299Y1890050D03*
X674899Y1911350D03*
X661299Y1909050D03*
X674899Y1920350D03*
X661299Y1918050D03*
X673899Y1938850D03*
X660299Y1936550D03*
Y1955550D03*
X673899Y1966850D03*
Y1957850D03*
X660299Y1964550D03*
X659299Y1976250D03*
X661999Y1986550D03*
X680499Y6550D03*
X694999Y62650D03*
Y81650D03*
X695999Y102650D03*
X688999Y196550D03*
X677999Y218050D03*
X683499Y263050D03*
Y248550D03*
X680500Y280700D03*
X682999Y300050D03*
Y319050D03*
X683999Y340050D03*
X694999Y480550D03*
X695999Y501550D03*
X695499Y521050D03*
X691399Y548350D03*
X692399Y569350D03*
X691899Y588850D03*
X690499Y623050D03*
X693999Y648150D03*
X678499Y671050D03*
X679299Y703050D03*
X678499Y688550D03*
X681899Y713650D03*
X696299Y741850D03*
X694599Y763450D03*
X685999Y780050D03*
X687099Y804650D03*
Y823650D03*
X688099Y844650D03*
X687099Y896350D03*
Y915350D03*
X688099Y936350D03*
X678299Y978350D03*
Y997350D03*
X694999Y993050D03*
X692999Y1011550D03*
Y1026050D03*
Y1043550D03*
X692499Y1063050D03*
Y1082050D03*
X689999Y1105550D03*
X695999Y1203050D03*
Y1235050D03*
Y1217550D03*
X684299Y1249550D03*
X695999Y1323350D03*
X677999Y1347550D03*
X694999Y1360050D03*
X680299Y1365850D03*
X694999Y1379050D03*
X681299Y1393150D03*
X692999Y1406550D03*
X694999Y1388050D03*
X678299Y1425050D03*
X692999Y1421050D03*
X686999Y1468850D03*
X685299Y1551950D03*
X681299Y1579150D03*
X693599Y1602450D03*
X686699Y1638650D03*
X691999Y1660550D03*
X693099Y1722350D03*
X690499Y1744950D03*
X694599Y1768450D03*
X690249Y1805634D03*
X693549Y1793134D03*
X686473Y1818375D03*
X686999Y1870250D03*
X690899Y1855850D03*
X696299Y1898850D03*
X676399Y1901150D03*
X695299Y1926450D03*
X685499Y1940050D03*
X696299Y1976250D03*
X678799Y1975750D03*
X685499Y1959050D03*
Y1968050D03*
X679499Y1987050D03*
X697999Y7050D03*
X712499Y6050D03*
X699699Y141750D03*
Y160750D03*
X700699Y181750D03*
X711999Y218050D03*
X711499Y252550D03*
X711999Y307550D03*
Y293050D03*
Y325050D03*
X711499Y344550D03*
X712699Y434450D03*
X713699Y455450D03*
X713199Y474950D03*
Y489450D03*
X712599Y521050D03*
X713599Y542050D03*
X713099Y561550D03*
X717099Y636050D03*
X702999Y656050D03*
Y688050D03*
Y670550D03*
X710899Y751150D03*
X716599Y736850D03*
X706999Y792550D03*
X707499Y773050D03*
X706999Y811550D03*
X707999Y832550D03*
X705999Y851050D03*
Y865550D03*
X707399Y899550D03*
Y918550D03*
X706499Y942550D03*
X713999Y1017050D03*
Y1031550D03*
X713499Y1068550D03*
X713999Y1049050D03*
X709999Y1105550D03*
X700499Y1118550D03*
X704299Y1132650D03*
X716999Y1148150D03*
X697499Y1153550D03*
X717999Y1169150D03*
X697499Y1172550D03*
X713399Y1178750D03*
X697999Y1184550D03*
X713599Y1214650D03*
X714399Y1199750D03*
X708699Y1243550D03*
X709699Y1264550D03*
X707899Y1346250D03*
X702299Y1404450D03*
X713899Y1386450D03*
X716899Y1459850D03*
X700899Y1450250D03*
X716199Y1503050D03*
X714599Y1533950D03*
X708899Y1549250D03*
X698599Y1568550D03*
X706700Y1579900D03*
X717099Y1702450D03*
X702599Y1730550D03*
X715999Y1744050D03*
X709099Y1751850D03*
X715999Y1763050D03*
Y1772050D03*
X706549Y1793634D03*
X705000Y1811900D03*
X711500Y1817700D03*
X704300Y1828400D03*
X697999Y1844550D03*
X706399Y1855850D03*
X705599Y1891850D03*
X716599Y1918450D03*
X698299Y1948050D03*
X711899Y1944050D03*
X709199Y1962950D03*
X717999Y1987550D03*
X702499D03*
X729999Y6550D03*
X725499Y23550D03*
X725999Y45050D03*
X725499Y62050D03*
X725999Y77550D03*
Y92050D03*
Y106550D03*
X738199Y137450D03*
X725999Y124050D03*
X725499Y143550D03*
Y162550D03*
X726499Y183550D03*
X728899Y204550D03*
X729499Y218550D03*
X723200Y275500D03*
X737999Y467050D03*
X738999Y488050D03*
X738499Y507550D03*
Y539550D03*
Y522050D03*
X737999Y559050D03*
X731499Y572050D03*
Y586550D03*
Y604050D03*
X729699Y640350D03*
X723499Y654850D03*
X739399Y688150D03*
X720899Y712250D03*
X732499Y729250D03*
X727099Y715050D03*
X733799Y761450D03*
X723999Y783350D03*
Y802350D03*
X724999Y823350D03*
X728499Y841850D03*
X729999Y862850D03*
Y881850D03*
X730999Y902850D03*
X723699Y936250D03*
Y955250D03*
X724699Y976250D03*
X734999Y1030550D03*
Y1045050D03*
Y1062550D03*
X727499Y1106050D03*
X737999Y1119050D03*
X720499Y1118550D03*
X727499Y1132650D03*
X737999Y1159550D03*
Y1187550D03*
Y1178550D03*
X735999Y1206050D03*
X725499Y1231650D03*
X735999Y1220550D03*
X725499Y1250650D03*
X723499Y1278150D03*
X725499Y1259650D03*
X723499Y1292650D03*
X719199Y1322350D03*
X739199Y1348950D03*
X734199Y1373850D03*
X736199Y1399050D03*
X737799Y1428350D03*
X721899Y1419050D03*
X719499Y1446650D03*
X729199Y1492750D03*
X735799Y1533650D03*
X734499Y1563550D03*
X722199Y1564250D03*
X719999Y1605050D03*
X732999Y1620050D03*
X738799Y1677250D03*
X727399Y1694350D03*
X739199Y1716750D03*
X721199Y1723750D03*
X729999Y1756450D03*
X729499Y1778750D03*
X728099Y1844750D03*
X723199Y1867950D03*
X725899Y1855350D03*
X732999Y1868550D03*
X728299Y1888850D03*
X732199Y1878750D03*
X728799Y1908150D03*
Y1933050D03*
X736799Y1919450D03*
X730499Y1954650D03*
X721499Y1974550D03*
X737499Y1987050D03*
X749499Y6550D03*
X751499Y48350D03*
X757499Y44050D03*
Y63050D03*
X758499Y84050D03*
X752099Y112150D03*
X749499Y218550D03*
X749899Y398550D03*
X750899Y419550D03*
X750399Y453550D03*
Y439050D03*
X755199Y488150D03*
X756199Y509150D03*
X755699Y528650D03*
X754499Y564650D03*
X755499Y585650D03*
X754999Y605150D03*
X747999Y670750D03*
X754999Y694050D03*
X749999Y700050D03*
X752999Y746842D03*
X757499Y745342D03*
X749799Y767450D03*
X743099Y785350D03*
X751999Y817050D03*
X751499Y855550D03*
Y836550D03*
X751599Y887350D03*
Y906350D03*
X752599Y927350D03*
X749999Y946550D03*
Y965550D03*
X751399Y1004550D03*
X750999Y986550D03*
X751399Y1023550D03*
X752399Y1052550D03*
X753999Y1100050D03*
X755600Y1149800D03*
X758799Y1171150D03*
Y1190150D03*
Y1199150D03*
X756799Y1232150D03*
Y1217650D03*
X757399Y1258650D03*
Y1239650D03*
X740499Y1252550D03*
X757399Y1267650D03*
X740499Y1270050D03*
X740799Y1298750D03*
X755399Y1300650D03*
Y1286150D03*
X742099Y1320650D03*
X758499Y1371050D03*
X754999Y1420050D03*
Y1437550D03*
X741099Y1450250D03*
Y1498150D03*
X747199Y1509150D03*
X755499Y1507550D03*
X758199Y1553650D03*
X755499Y1568550D03*
X743400Y1578700D03*
X751300Y1604900D03*
X756299Y1679050D03*
X750099Y1694950D03*
X756499Y1712150D03*
X747499Y1734350D03*
X751899Y1752150D03*
X747799Y1766750D03*
X744049Y1791634D03*
X740549Y1802634D03*
X753949Y1798194D03*
X755000Y1825000D03*
X740549Y1810384D03*
X747599Y1844250D03*
X744699Y1868450D03*
X758399Y1868350D03*
X743399Y1855850D03*
X743799Y1888850D03*
X753699Y1879250D03*
X755299Y1902150D03*
X739799D03*
X755500Y1914500D03*
X746499Y1974250D03*
X759114Y1957673D03*
X754999Y1987550D03*
X764999Y6550D03*
X763399Y24150D03*
X774399Y54050D03*
X775399Y80250D03*
X778399Y105250D03*
X767399Y140150D03*
X760799Y181950D03*
X779399Y200550D03*
X766999Y219050D03*
X770999Y302050D03*
Y290050D03*
Y295550D03*
X763571Y295622D03*
X777999Y296050D03*
X760778Y345050D03*
X768178Y333964D03*
X774999Y476550D03*
Y462050D03*
Y494050D03*
X774499Y513550D03*
Y532550D03*
X775499Y553550D03*
X764599Y655750D03*
X766499Y699050D03*
Y705550D03*
Y732842D03*
X762999Y734550D03*
X778999Y806950D03*
X763099Y796350D03*
X775199Y839250D03*
Y858250D03*
X776199Y879250D03*
X772199Y920650D03*
Y939650D03*
X773199Y960650D03*
X776899Y988050D03*
Y1007050D03*
X777899Y1028050D03*
X760999Y1095550D03*
X773499Y1101050D03*
X769499D03*
X773499Y1105050D03*
X769499D03*
X767083Y1134550D03*
X768199Y1138590D03*
X762499Y1335550D03*
X779399Y1361850D03*
X762499Y1353050D03*
X773999Y1393450D03*
X763399Y1401450D03*
X769300Y1488100D03*
X779000Y1488400D03*
X771399Y1474550D03*
X770999Y1500050D03*
X780499D03*
X773499Y1509050D03*
X769499D03*
X771225Y1539474D03*
X767936Y1540336D03*
X768500Y1577500D03*
X776999Y1647650D03*
X765099Y1664950D03*
X770399Y1699650D03*
X779999Y1717050D03*
X770099Y1730350D03*
X779899Y1748150D03*
X765600Y1756800D03*
X774500Y1788000D03*
X770999Y1820550D03*
X765099Y1844750D03*
X779699Y1867950D03*
X779399Y1855850D03*
X763899D03*
X780799Y1888850D03*
X763299Y1888350D03*
X769199Y1879250D03*
X774499Y1908050D03*
X765999D03*
X775999Y1916050D03*
X768499Y1917550D03*
X767999Y1945173D03*
X764908Y1946592D03*
X777499Y1987550D03*
X784499Y6050D03*
X801999Y6550D03*
X796999Y27050D03*
X797499Y48550D03*
X796999Y65550D03*
X797499Y81050D03*
Y95550D03*
Y110050D03*
X796599Y123450D03*
X797499Y127550D03*
X796999Y147050D03*
Y166050D03*
X797999Y187050D03*
X786499Y219050D03*
X800999Y216550D03*
X785499Y291050D03*
X786978Y298529D03*
X784499Y334050D03*
X789999Y570050D03*
Y602050D03*
Y584550D03*
X782999Y699550D03*
X784939Y733550D03*
X802499Y814550D03*
X801999Y834050D03*
Y853050D03*
X800999Y892550D03*
Y907050D03*
Y924550D03*
X800499Y944050D03*
Y963050D03*
X801499Y984050D03*
X800999Y1005550D03*
Y1020050D03*
Y1037550D03*
X783999Y1096550D03*
X789499Y1099550D03*
X784439Y1136550D03*
X790999Y1194550D03*
Y1175550D03*
X791499Y1206550D03*
X789499Y1225050D03*
Y1257050D03*
Y1239550D03*
X788999Y1278150D03*
X791999Y1294450D03*
X795299Y1326650D03*
X799999Y1340550D03*
X798299Y1344250D03*
X799999Y1358050D03*
X781999Y1434650D03*
X786500Y1488600D03*
X801300Y1489000D03*
X786999Y1506550D03*
X784577Y1535628D03*
X797299Y1646650D03*
X802899Y1670550D03*
X782999Y1668050D03*
Y1687050D03*
X783499Y1699050D03*
X794499Y1734550D03*
X787900Y1758800D03*
X788000Y1788000D03*
X791999Y1819050D03*
X783499Y1827050D03*
X801099Y1844750D03*
X785599D03*
X791799Y1855850D03*
X797199Y1868450D03*
X788699Y1878750D03*
X783499Y1907050D03*
X790499Y1913050D03*
X785939Y1946800D03*
X789299Y1983850D03*
X792999Y1987550D03*
X818999Y6050D03*
X817599Y43750D03*
X813299Y49350D03*
Y68350D03*
X814299Y89350D03*
X813299Y110850D03*
X821199Y137450D03*
X805899Y126150D03*
X820749Y163850D03*
X813249Y163800D03*
X821999Y193116D03*
X819299Y413250D03*
Y394250D03*
X820299Y434250D03*
X802999Y466050D03*
X803999Y487050D03*
X803499Y506550D03*
Y538550D03*
Y521050D03*
X802999Y558050D03*
X814499Y569550D03*
Y601550D03*
Y584050D03*
X811499Y767550D03*
Y782050D03*
Y799550D03*
X802999Y874050D03*
X808299Y1175850D03*
X806599Y1189750D03*
X803599Y1211050D03*
X810199Y1229350D03*
Y1248350D03*
Y1257350D03*
X808199Y1275850D03*
Y1290350D03*
X822199Y1335250D03*
X819199Y1353550D03*
X806499Y1390550D03*
X803299Y1426650D03*
X806499Y1408050D03*
X805899Y1464250D03*
X813300Y1604100D03*
X803599Y1618350D03*
X814599Y1642650D03*
X823499Y1674050D03*
X808899Y1698450D03*
X823499Y1693050D03*
Y1702050D03*
X824100Y1719900D03*
X819400Y1721900D03*
X819200Y1727100D03*
X808299Y1755250D03*
X812000Y1799500D03*
X821249Y1791250D03*
X811000Y1793000D03*
X822499Y1815164D03*
X809299Y1856350D03*
X818900Y1870800D03*
X806199Y1879250D03*
X813599Y1979950D03*
X812499Y1987050D03*
X836499Y6550D03*
X824899Y25150D03*
X844799Y19850D03*
X841499Y135550D03*
X837499Y138550D03*
X838499Y145050D03*
X827499Y163550D03*
X839249Y164050D03*
X836500Y274950D03*
X827499Y313424D03*
X838499Y352050D03*
X839299Y390950D03*
Y409950D03*
X840299Y430950D03*
X824899Y500450D03*
X825899Y521450D03*
X825399Y540950D03*
X834599Y543050D03*
X835599Y564050D03*
X835099Y583550D03*
X835150Y677650D03*
X836149Y714050D03*
X835999Y767050D03*
X837799Y754150D03*
X835999Y781550D03*
Y799050D03*
X825199Y850850D03*
X827699Y873450D03*
Y892450D03*
X828699Y913450D03*
X826999Y963150D03*
Y982150D03*
X827999Y1003150D03*
X841999Y1118550D03*
X836149D03*
X839999Y1157550D03*
X831499Y1181550D03*
Y1209550D03*
Y1200550D03*
X829499Y1228050D03*
Y1242550D03*
X828199Y1267850D03*
X826199Y1294450D03*
X831499Y1324950D03*
X841999Y1341050D03*
Y1358550D03*
X825500Y1379000D03*
X834499Y1397550D03*
X836600Y1416500D03*
X836625Y1487400D03*
X843999Y1523550D03*
X839499D03*
X839899Y1562050D03*
X825999Y1578050D03*
X826499Y1609050D03*
X827199Y1622750D03*
X841499Y1638950D03*
X837199Y1660550D03*
X839199Y1683550D03*
X842799Y1701150D03*
X829200Y1719800D03*
X844499Y1788050D03*
X842500Y1799000D03*
X827999Y1791550D03*
X829799Y1856350D03*
X833199Y1868450D03*
X842199Y1879250D03*
X833100Y1878500D03*
X843999Y1928550D03*
X838999D03*
X840999Y1970550D03*
X829499Y1980250D03*
X829999Y1987550D03*
X855999Y6550D03*
X860799Y24150D03*
X853999Y132550D03*
X849999Y145550D03*
X861999Y146550D03*
X847450Y246666D03*
X850999Y246550D03*
X858478Y274050D03*
X858400Y352300D03*
X847999Y352550D03*
X854499Y387550D03*
Y373050D03*
Y405050D03*
X853999Y424550D03*
Y443550D03*
X854999Y464550D03*
X860199Y525050D03*
X861199Y546050D03*
X860699Y565550D03*
X861800Y591200D03*
X860499Y607550D03*
X851197Y652032D03*
X847493Y651981D03*
X860796Y678632D03*
X859999Y713050D03*
Y767550D03*
X856299Y753150D03*
X846799Y754150D03*
X865000Y752100D03*
X859999Y782050D03*
Y799550D03*
X847799Y828250D03*
X857099Y873450D03*
X866199Y920350D03*
Y901350D03*
X850999Y962550D03*
Y943550D03*
X851999Y983550D03*
X847355Y1058094D03*
X851042Y1058047D03*
X860133Y1084142D03*
X859999Y1118550D03*
X846499Y1170450D03*
X856400Y1157700D03*
X848999Y1158050D03*
X863300Y1153800D03*
X845799Y1190450D03*
X849799Y1199750D03*
X851999Y1237550D03*
Y1218550D03*
X852499Y1249550D03*
X850499Y1268050D03*
X860099Y1295450D03*
X850499Y1300050D03*
Y1282550D03*
X860799Y1358925D03*
X848861Y1462463D03*
X852429Y1462948D03*
X858827Y1485696D03*
X861999Y1522550D03*
X850099Y1572250D03*
X858400Y1561900D03*
X850499Y1562050D03*
X865300Y1557700D03*
X864000Y1578200D03*
X849900Y1605100D03*
X852499Y1621350D03*
X855799Y1658250D03*
X864099Y1683550D03*
X853799Y1790850D03*
X863099Y1813150D03*
X851500Y1821400D03*
X849375Y1824982D03*
X854905Y1825583D03*
X862499Y1823550D03*
X854977Y1818994D03*
X854480Y1867578D03*
X849999Y1867550D03*
X863788Y1866953D03*
X865501Y1858747D03*
X859314Y1891365D03*
X861414Y1928550D03*
X850499Y1977950D03*
X856999Y1970050D03*
X849999Y1970550D03*
X865200Y1968000D03*
X864999Y1987050D03*
X849499D03*
X871499Y6550D03*
X885999Y21150D03*
X872499Y133050D03*
X871499Y146050D03*
X882499Y147050D03*
X871786Y218924D03*
Y203924D03*
X874928Y238822D03*
X887400Y233555D03*
X871786Y233924D03*
X874790Y244748D03*
X887400Y259700D03*
X879878Y247724D03*
X871999Y283924D03*
X872136Y273924D03*
X886600Y303924D03*
X886200Y313924D03*
X870600Y346700D03*
X875799Y386250D03*
Y405250D03*
X876799Y426250D03*
X884399Y443450D03*
Y462450D03*
X885399Y483450D03*
X870719Y609705D03*
X870773Y624705D03*
X874999Y644550D03*
X870719Y639705D03*
X875270Y650059D03*
X887401Y665000D03*
X881125Y652050D03*
X871786Y679436D03*
Y709482D03*
X871499Y689436D03*
X871385Y719436D03*
X884499Y767050D03*
Y781550D03*
Y799050D03*
X873999Y830550D03*
Y845050D03*
Y862550D03*
X886999Y907350D03*
X867199Y941350D03*
X886999Y947250D03*
X870777Y1014948D03*
X870468Y1030227D03*
X886919Y1044478D03*
X870298Y1045227D03*
X874733Y1055792D03*
X874999Y1049550D03*
X880033Y1058592D03*
X887400Y1070600D03*
X872086Y1084948D03*
X871999Y1094948D03*
X871499Y1124948D03*
X872086Y1114948D03*
X871399Y1182850D03*
Y1201850D03*
Y1210850D03*
X869399Y1229350D03*
Y1243850D03*
X872099Y1268150D03*
X871399Y1291450D03*
X875399Y1322650D03*
X868499Y1392550D03*
Y1410050D03*
X871836Y1420460D03*
X886913Y1449010D03*
X871836Y1435460D03*
X874499Y1460550D03*
X874986Y1454983D03*
X879727Y1463696D03*
X871836Y1450460D03*
X887499Y1476050D03*
X872086Y1490460D03*
X871999Y1500460D03*
Y1520460D03*
X872086Y1530460D03*
X873099Y1572550D03*
X886900Y1604100D03*
X866499Y1603050D03*
Y1612050D03*
X868099Y1635650D03*
X887299Y1620050D03*
X877699Y1646650D03*
X882999Y1678250D03*
X866699Y1770950D03*
X879399Y1798150D03*
X869634Y1826876D03*
X871836Y1840972D03*
X887499Y1855550D03*
X869999Y1855972D03*
X887401Y1881500D03*
X871921Y1905972D03*
X871421Y1895972D03*
X872086Y1925972D03*
Y1935972D03*
X879399Y1974550D03*
X873399Y1963650D03*
X868699Y1983250D03*
X884499Y1986550D03*
X890999Y6050D03*
X908499Y6550D03*
X898999Y99050D03*
X889999Y132550D03*
X891999Y146050D03*
X896999Y141550D03*
X906999Y243150D03*
Y224150D03*
X907999Y264150D03*
X906399Y295250D03*
Y314250D03*
X907399Y335250D03*
X904999Y370550D03*
Y385050D03*
Y402550D03*
X904499Y422050D03*
Y441050D03*
X905499Y462050D03*
X898999Y622050D03*
Y604550D03*
X894000Y642400D03*
X900999Y652550D03*
Y670050D03*
X895999Y702550D03*
Y720050D03*
X898499Y830050D03*
Y844550D03*
X889699Y876050D03*
X898499Y862050D03*
X897299Y1182450D03*
X887999Y1209350D03*
X892499Y1224550D03*
Y1252550D03*
Y1243550D03*
X890499Y1271050D03*
Y1285550D03*
X890999Y1336550D03*
Y1354050D03*
X894499Y1423550D03*
Y1441050D03*
X895499Y1488050D03*
X902759Y1509585D03*
X894499Y1522050D03*
Y1539550D03*
X907500Y1604000D03*
X895999Y1661250D03*
X903599Y1686850D03*
X902900Y1709800D03*
X903299Y1814750D03*
X894999Y1829050D03*
X905299Y1852650D03*
X894000Y1868452D03*
X900299Y1876950D03*
X897299Y1904150D03*
X907599Y1930050D03*
X897599Y1938750D03*
X904299Y1954950D03*
X901999Y1987050D03*
X923999Y6050D03*
X920900Y54700D03*
X916499Y115050D03*
X913699Y484650D03*
Y503650D03*
X914699Y524650D03*
X922049Y574375D03*
X918999Y641550D03*
Y656050D03*
Y673550D03*
X918499Y693050D03*
Y712050D03*
X921899Y744850D03*
X919499Y733050D03*
X921899Y759350D03*
Y776850D03*
X921399Y796350D03*
X922399Y836350D03*
X921399Y815350D03*
X920399Y854850D03*
Y869350D03*
Y886850D03*
X919899Y906350D03*
Y925350D03*
X920899Y946350D03*
X922049Y978575D03*
X921499Y999050D03*
Y1013550D03*
Y1031050D03*
X920999Y1050550D03*
Y1069550D03*
X925499Y1103550D03*
X921999Y1090550D03*
X925499Y1118050D03*
Y1135550D03*
X924999Y1174050D03*
Y1155050D03*
X925999Y1195050D03*
Y1207050D03*
Y1221550D03*
Y1239050D03*
X925499Y1258550D03*
Y1277550D03*
X926499Y1298550D03*
X928499Y1325350D03*
X925999Y1365050D03*
Y1379550D03*
Y1397050D03*
X925499Y1416550D03*
Y1435550D03*
X926499Y1456550D03*
X924999Y1485550D03*
Y1471050D03*
Y1503050D03*
X914599Y1521650D03*
X924499Y1522550D03*
X910899Y1549250D03*
X924499Y1541550D03*
X909700Y1576400D03*
X925499Y1562550D03*
X925599Y1612050D03*
X923599Y1634350D03*
X908899Y1630050D03*
X914899Y1657550D03*
X922599Y1682150D03*
X911299Y1800850D03*
X921549Y1788475D03*
X928000Y1818500D03*
X922899Y1853650D03*
X914999Y1868050D03*
Y1887050D03*
X914899Y1912450D03*
X915499Y1899050D03*
X916599Y1942650D03*
X914899Y1972250D03*
X921499Y1986550D03*
X941499Y6550D03*
X946899Y122550D03*
X939199Y142050D03*
X939549Y175175D03*
X932499Y191550D03*
Y206050D03*
Y223550D03*
X931999Y243050D03*
Y262050D03*
X932999Y283050D03*
X933499Y304050D03*
Y318550D03*
Y336050D03*
X932999Y355550D03*
Y374550D03*
X933999Y395550D03*
X933499Y429550D03*
Y415050D03*
Y447050D03*
X932999Y466550D03*
Y485550D03*
X933999Y506550D03*
X935499Y539050D03*
Y524550D03*
Y556550D03*
X934999Y576050D03*
X950299Y599650D03*
X934999Y595050D03*
X950299Y614150D03*
X935999Y616050D03*
X950299Y631650D03*
X949799Y651150D03*
Y670150D03*
X950799Y691150D03*
X944499Y750050D03*
Y735550D03*
Y767550D03*
X943999Y787050D03*
Y806050D03*
X944999Y827050D03*
X942999Y845550D03*
Y877550D03*
Y860050D03*
X942499Y897050D03*
Y916050D03*
X943499Y937050D03*
X949299Y977450D03*
Y991950D03*
Y1009450D03*
X948799Y1047950D03*
Y1028950D03*
X949799Y1068950D03*
Y1080950D03*
X950699Y1107750D03*
Y1122250D03*
Y1139750D03*
X950199Y1159250D03*
Y1178250D03*
X950699Y1262750D03*
Y1281750D03*
X943799Y1342950D03*
Y1380850D03*
X944000Y1391900D03*
X946700Y1426500D03*
X944000Y1511300D03*
X943199Y1531650D03*
X933199Y1577550D03*
X944499Y1632650D03*
X940499Y1656950D03*
X941499Y1679550D03*
X931499Y1702050D03*
X949799Y1756250D03*
X941800Y1787700D03*
X941499Y1776250D03*
X934200Y1793500D03*
X932199Y1801850D03*
X937199Y1869950D03*
X937499Y1893850D03*
X938199Y1917150D03*
X947499Y1936050D03*
X930999Y1931050D03*
X945199Y1946350D03*
X930999Y1950050D03*
X946199Y1966650D03*
X931499Y1962050D03*
X930199Y1979550D03*
X936999Y1986550D03*
X960999Y6550D03*
X954799Y17850D03*
X965999Y47050D03*
Y56050D03*
Y64050D03*
X966499Y73050D03*
Y82050D03*
X958999Y96050D03*
X961499Y100050D03*
X968399Y137150D03*
X967399Y180350D03*
X958799Y167350D03*
X956099Y181350D03*
X952799Y199150D03*
Y213650D03*
Y231150D03*
X952299Y250650D03*
Y269650D03*
X953299Y290650D03*
X952799Y324650D03*
Y310150D03*
Y342150D03*
X952299Y361650D03*
Y380650D03*
X953299Y401650D03*
X954799Y434150D03*
Y419650D03*
Y451650D03*
X966199Y473350D03*
Y492350D03*
X951799Y489650D03*
X967199Y513350D03*
X951799Y504150D03*
Y521650D03*
X966499Y552050D03*
X951299Y560150D03*
Y541150D03*
X966799Y566350D03*
X952299Y581150D03*
X966799Y585350D03*
X967799Y606350D03*
X969499Y639050D03*
Y653550D03*
Y671050D03*
X968999Y709550D03*
Y690550D03*
X969999Y730550D03*
Y744250D03*
Y758750D03*
Y776250D03*
X969499Y795750D03*
Y814750D03*
X970499Y835750D03*
Y847750D03*
Y862250D03*
X969999Y899250D03*
X970499Y879750D03*
X969999Y918250D03*
X970999Y939250D03*
X965999Y954550D03*
X971999Y996550D03*
Y1011050D03*
Y1028550D03*
X971499Y1067050D03*
Y1048050D03*
X951199Y1211250D03*
Y1199250D03*
Y1225750D03*
Y1243250D03*
X951699Y1302750D03*
X965099Y1324350D03*
X952499Y1361850D03*
X964400Y1409700D03*
X966600Y1529100D03*
X961400Y1528700D03*
X961900Y1522400D03*
X967100Y1522800D03*
X962100Y1516000D03*
X967300Y1516400D03*
X961600Y1534400D03*
X972000Y1547500D03*
X966100D03*
X960900Y1547100D03*
X961400Y1540800D03*
X966600Y1541200D03*
X966800Y1534800D03*
X961600Y1552900D03*
X966800Y1553300D03*
X972000Y1566000D03*
X966100D03*
X960900Y1565600D03*
X961400Y1559300D03*
X966600Y1559700D03*
X961900Y1572400D03*
X967100Y1572800D03*
X966400Y1585500D03*
X961200Y1585100D03*
X961700Y1578800D03*
X966900Y1579200D03*
X966500Y1592000D03*
X961300Y1591600D03*
X966300Y1598400D03*
X961100Y1598000D03*
X960600Y1604300D03*
X971700Y1604700D03*
X965800D03*
X957799Y1646950D03*
X955499Y1690850D03*
X958799Y1715750D03*
X965349Y1742000D03*
X954499Y1783550D03*
X971000Y1803000D03*
X971500Y1871500D03*
X966799Y1892150D03*
X955499Y1893050D03*
Y1902050D03*
X954099Y1915450D03*
X955799Y1951950D03*
X971499Y1956050D03*
Y1937050D03*
X953799Y1977950D03*
X971499Y1965050D03*
X956499Y1986050D03*
X976499Y6550D03*
X974699Y21450D03*
X991399Y22450D03*
X977399Y44050D03*
X974699Y64650D03*
X991999Y56050D03*
X983099Y83650D03*
X977699Y109150D03*
X981099Y123450D03*
X988699Y174350D03*
X982999Y189050D03*
Y203550D03*
Y221050D03*
X982499Y240550D03*
Y259550D03*
X983499Y280550D03*
X983999Y301550D03*
Y316050D03*
Y333550D03*
X983499Y353050D03*
Y372050D03*
X983999Y412550D03*
X984499Y393050D03*
X983999Y427050D03*
Y444550D03*
X983499Y464050D03*
Y483050D03*
X984499Y504050D03*
X985999Y536550D03*
Y522050D03*
Y554050D03*
X985499Y573550D03*
Y592550D03*
X986499Y613550D03*
X992999Y894550D03*
Y913550D03*
X972499Y1088050D03*
X975999Y1101050D03*
Y1115550D03*
X975499Y1152550D03*
X975999Y1133050D03*
X975499Y1171550D03*
X976499Y1192550D03*
Y1204550D03*
Y1219050D03*
Y1236550D03*
X975999Y1256050D03*
Y1275050D03*
X976999Y1296050D03*
X975100Y1342600D03*
X976499Y1362550D03*
Y1377050D03*
X992500Y1397300D03*
X973200Y1516400D03*
X972500Y1529100D03*
X973000Y1522800D03*
X972700Y1534800D03*
X972500Y1541200D03*
X972700Y1553300D03*
X972500Y1559700D03*
X973000Y1572800D03*
X972300Y1585500D03*
X972800Y1579200D03*
X972400Y1592000D03*
X972200Y1598400D03*
X981200Y1618002D03*
X990425Y1633898D03*
X987029Y1634075D03*
X989502Y1646000D03*
X988800Y1658300D03*
X989000Y1663802D03*
X987200Y1675600D03*
X989900Y1678800D03*
X989999Y1718050D03*
X993299Y1734350D03*
X976600Y1757100D03*
X976399Y1772250D03*
Y1791150D03*
X974699Y1914450D03*
X991999Y1915750D03*
X992299Y1929050D03*
X980999Y1933350D03*
X987999Y1949050D03*
Y1971950D03*
X989999Y1962650D03*
X973999Y1986550D03*
X995999Y6050D03*
X1013499Y6550D03*
X1002699Y40050D03*
X1005299Y71350D03*
X994399Y101250D03*
X1010599Y115550D03*
X1005299Y179950D03*
Y194450D03*
Y211950D03*
X1004799Y231450D03*
Y250450D03*
X1005799Y271450D03*
X1005299Y305450D03*
Y290950D03*
Y322950D03*
X1004799Y342450D03*
Y361450D03*
X1005799Y382450D03*
X1007299Y400450D03*
Y432450D03*
Y414950D03*
X1000699Y463350D03*
Y482350D03*
X1001699Y503350D03*
X1003999Y526850D03*
X1003499Y546350D03*
Y565350D03*
X1004499Y586350D03*
X1005999Y618850D03*
Y604350D03*
Y636350D03*
X994999Y747550D03*
Y733050D03*
Y765050D03*
X994499Y784550D03*
Y803550D03*
X995499Y824550D03*
X993499Y857550D03*
Y843050D03*
Y875050D03*
X994499Y941550D03*
X993999Y934550D03*
X994499Y956050D03*
Y973550D03*
X993999Y993050D03*
Y1012050D03*
X994999Y1033050D03*
Y1045050D03*
X998599Y1110950D03*
Y1096450D03*
Y1128450D03*
X998099Y1147950D03*
Y1166950D03*
X999099Y1187950D03*
Y1214450D03*
Y1199950D03*
Y1231950D03*
X998599Y1251450D03*
Y1270450D03*
X999599Y1291450D03*
X996500Y1324800D03*
X1000700Y1358100D03*
X994200Y1421500D03*
X1008999Y1702450D03*
X1008599Y1716050D03*
X994999Y1748950D03*
X999999Y1775250D03*
X1009999Y1797450D03*
X993499Y1805550D03*
X1007599Y1818450D03*
X993499Y1824550D03*
X1003599Y1846650D03*
X993499Y1833550D03*
X1011299Y1860650D03*
X995699Y1858950D03*
X1001599Y1921450D03*
X1000999Y1946350D03*
X1002500Y1953500D03*
X1005000Y1980500D03*
X1022000Y15500D03*
X1016499Y1301050D03*
X1022599Y1322950D03*
X1023300Y1344400D03*
X1024300Y1365200D03*
Y1393600D03*
X1022299Y1715750D03*
X1016899Y1731650D03*
X1020299Y1746650D03*
X1015299Y1765950D03*
X1026899Y1768550D03*
G54D18*
X78150Y28858D03*
Y178464D03*
Y434370D03*
Y583976D03*
Y839882D03*
Y989488D03*
Y1245394D03*
Y1395000D03*
Y1650906D03*
Y1800512D03*
X158071Y191614D03*
Y341220D03*
Y597126D03*
Y746732D03*
Y1002638D03*
Y1152244D03*
Y1408150D03*
Y1557756D03*
Y1813662D03*
Y1963268D03*
X886417Y191614D03*
Y341220D03*
Y597126D03*
Y746732D03*
Y1002638D03*
Y1152244D03*
Y1408150D03*
Y1557756D03*
Y1813662D03*
Y1963268D03*
G54D10*
X-38436Y23633D03*
X-36811Y1104775D03*
X-35919Y1969497D03*
X1072493Y21507D03*
X1075940Y1769358D03*
G54D17*
X68898Y17047D03*
Y190275D03*
Y422559D03*
Y595787D03*
Y828071D03*
Y1001299D03*
Y1233583D03*
Y1406811D03*
Y1639095D03*
Y1812323D03*
G54D14*
X9843Y353144D03*
Y717711D03*
Y762617D03*
Y875216D03*
Y1337396D03*
Y1701963D03*
Y1746869D03*
Y1859468D03*
G54D23*
X1019291Y1416024D03*
Y1694212D03*
G54D12*
X10000Y16500D03*
X11999Y53550D03*
X11499Y34050D03*
X11999Y69050D03*
Y88550D03*
X11499Y106050D03*
X11999Y124550D03*
X11499Y142050D03*
X11999Y177050D03*
Y161550D03*
Y196550D03*
X11499Y214050D03*
X9499Y229050D03*
X8999Y246550D03*
X9499Y281550D03*
Y266050D03*
Y301050D03*
X8999Y318550D03*
Y889550D03*
X8499Y907050D03*
X8999Y942050D03*
Y926550D03*
Y961550D03*
X8499Y979050D03*
X8999Y988550D03*
Y1025550D03*
X8499Y1006050D03*
X8999Y1041050D03*
Y1060550D03*
X8499Y1089050D03*
Y1078050D03*
X7999Y1106550D03*
X8499Y1126050D03*
Y1141550D03*
Y1161050D03*
X7999Y1192550D03*
Y1178550D03*
X7499Y1210050D03*
X7999Y1229550D03*
Y1245050D03*
Y1264550D03*
X7499Y1282050D03*
X8299Y1320050D03*
X8799Y1302550D03*
X21499Y1073250D03*
X21399Y1090850D03*
X21299Y1300250D03*
X21799Y1282750D03*
X821499Y314050D03*
X838999Y313550D03*
X863999D03*
X855350Y1703201D03*
X879200Y1698700D03*
X879900Y1709300D03*
X883900Y1709500D03*
X875900D03*
X872950Y1744401D03*
X893200Y1721300D03*
Y1730000D03*
X994999Y1986550D03*
X1020499Y50550D03*
X1020999Y33050D03*
Y70050D03*
Y85550D03*
Y105050D03*
X1020499Y122550D03*
X1020999Y158550D03*
X1021499Y141050D03*
Y178050D03*
Y193550D03*
Y213050D03*
X1020999Y230550D03*
Y252050D03*
X1020499Y269550D03*
X1020999Y304550D03*
Y289050D03*
Y324050D03*
X1020499Y341550D03*
Y391550D03*
X1020999Y374050D03*
Y411050D03*
Y426550D03*
Y446050D03*
X1020499Y463550D03*
X1021999Y486550D03*
X1021499Y504050D03*
X1021999Y539050D03*
Y523550D03*
Y558550D03*
X1021499Y576050D03*
X1020499Y623050D03*
X1020999Y605550D03*
Y642550D03*
Y658050D03*
Y677550D03*
X1020499Y695050D03*
X1020999Y720050D03*
X1020499Y737550D03*
X1020999Y772550D03*
Y757050D03*
Y792050D03*
X1020499Y809550D03*
Y828050D03*
X1019999Y845550D03*
X1020499Y865050D03*
Y880550D03*
X1019999Y917550D03*
X1020499Y900050D03*
X1019999Y934050D03*
X1019499Y951550D03*
X1019999Y971050D03*
Y986550D03*
X1019499Y1023550D03*
X1019999Y1006050D03*
Y1043050D03*
Y1058550D03*
X1020499Y1081550D03*
X1019999Y1099050D03*
X1020499Y1118550D03*
Y1134050D03*
X1019499Y1146050D03*
X1018999Y1163550D03*
X1019499Y1183050D03*
Y1198550D03*
X1016999Y1219050D03*
X1016499Y1236550D03*
X1016999Y1256050D03*
Y1271550D03*
X1022999Y1784550D03*
X1022499Y1802050D03*
X1022999Y1821550D03*
Y1837050D03*
X1020999Y1860050D03*
X1020499Y1877550D03*
X1020999Y1912550D03*
Y1897050D03*
X1017499Y1954550D03*
X1017999Y1937050D03*
X1023000Y1973000D03*
X1017999Y1987050D03*
G54D20*
X117499Y1745050D03*
X123499Y1747050D03*
X144499Y1745550D03*
X137999Y1747723D03*
X129999Y1747050D03*
G54D13*
X29531Y309549D03*
Y1029510D03*
X17720Y1903132D03*
X271657Y267699D03*
Y673210D03*
Y1078722D03*
Y1484234D03*
Y1889746D03*
X994098Y149588D03*
Y673210D03*
Y1068880D03*
%LPC*%
G75*
G54D24*
G01X-87137Y-139897D02*
Y-107897D01*
G01X-75137Y-123897D02*
G02I-12000J0D01*
G01X-80287D02*
G02I-6850J0D01*
G01X-71137D02*
X-103137D01*
G01X-71137Y-139897D02*
Y-219897D01*
G01D02*
X1129963D01*
G01X-71137Y-175397D02*
X1129963D01*
G01X-71137Y-139897D02*
X1129963D01*
G01X342463D02*
Y-219897D01*
G01X479963Y-139897D02*
Y-219897D01*
G01X594963Y-139897D02*
Y-219897D01*
G01X762463Y-139897D02*
Y-219897D01*
G01X932463Y-139897D02*
Y-219897D01*
G01X1129963Y-139897D02*
Y-219897D01*
G01X1157963Y-123897D02*
G02I-12000J0D01*
G01X1152813D02*
G02I-6850J0D01*
G01X1161963D02*
X1129963D01*
G01X1145963Y-139897D02*
Y-107897D01*
G54D25*
G01X-53190Y-209897D02*
Y-192397D01*
G01X-44894D02*
X-53190Y-203189D01*
G01X-43584Y-209897D02*
X-49479Y-198231D01*
G01X-35909Y-209897D02*
Y-192397D01*
X-25865Y-209897D01*
Y-192397D01*
G01X-13387Y-209897D02*
X-15134Y-209605D01*
X-16662Y-208439D01*
X-17972Y-206689D01*
X-18846Y-204647D01*
X-19282Y-202314D01*
Y-199980D01*
X-18846Y-197647D01*
X-17972Y-195605D01*
X-16662Y-193856D01*
X-15134Y-192689D01*
X-13387Y-192397D01*
X-11641Y-192689D01*
X-10112Y-193856D01*
X-8802Y-195605D01*
X-7928Y-197647D01*
X-7492Y-199980D01*
Y-202314D01*
X-7928Y-204647D01*
X-8802Y-206689D01*
X-10112Y-208439D01*
X-11641Y-209605D01*
X-13387Y-209897D01*
G01X-472D02*
X8698Y-192397D01*
G01X-472D02*
X8698Y-209897D01*
G01X34310D02*
Y-192397D01*
X38676D01*
X40423Y-193272D01*
X41733Y-194439D01*
X42825Y-196188D01*
X43698Y-198231D01*
X43916Y-201147D01*
X43698Y-204064D01*
X42825Y-206106D01*
X41733Y-207856D01*
X40423Y-209022D01*
X38676Y-209897D01*
X34310D01*
G01X52246D02*
Y-192397D01*
X57705D01*
X59451Y-193272D01*
X60543Y-194439D01*
X60980Y-196772D01*
X60543Y-199106D01*
X59233Y-200564D01*
X57705Y-201439D01*
X52246D01*
G01X57705D02*
X60980Y-209897D01*
G01X71493Y-192397D02*
X76733D01*
G01X74113D02*
Y-209897D01*
G01X71493D02*
X76733D01*
G01X86154Y-192397D02*
X91613Y-209897D01*
X97072Y-192397D01*
G01X113480Y-209897D02*
X104746D01*
Y-192397D01*
X113480D01*
G01X109986Y-200855D02*
X104746D01*
G01X139746Y-209897D02*
Y-192397D01*
X144986D01*
X146733Y-193272D01*
X148043Y-195314D01*
X148480Y-197647D01*
X148043Y-199980D01*
X146951Y-201730D01*
X144986Y-202606D01*
X139746D01*
G01X157246Y-192397D02*
Y-209897D01*
X165980D01*
G01X173654D02*
X179113Y-192397D01*
X184572Y-209897D01*
G01X182606Y-203772D02*
X175619D01*
G01X191591Y-209897D02*
Y-192397D01*
X201635Y-209897D01*
Y-192397D01*
G01X218480Y-209897D02*
X209746D01*
Y-192397D01*
X218480D01*
G01X214986Y-200855D02*
X209746D01*
G01X250859Y-200564D02*
X251733Y-199689D01*
X252388Y-198231D01*
X252825Y-196188D01*
X252388Y-194439D01*
X251515Y-193272D01*
X249986Y-192397D01*
X244091D01*
Y-209897D01*
X251296D01*
X252825Y-208731D01*
X253698Y-206980D01*
X254135Y-204939D01*
X253698Y-202897D01*
X252388Y-201147D01*
X250859Y-200564D01*
X244091D01*
G01X266613Y-209897D02*
X264866Y-209605D01*
X263338Y-208439D01*
X262028Y-206689D01*
X261154Y-204647D01*
X260718Y-202314D01*
Y-199980D01*
X261154Y-197647D01*
X262028Y-195605D01*
X263338Y-193856D01*
X264866Y-192689D01*
X266613Y-192397D01*
X268359Y-192689D01*
X269888Y-193856D01*
X271198Y-195605D01*
X272072Y-197647D01*
X272508Y-199980D01*
Y-202314D01*
X272072Y-204647D01*
X271198Y-206689D01*
X269888Y-208439D01*
X268359Y-209605D01*
X266613Y-209897D01*
G01X278654D02*
X284113Y-192397D01*
X289572Y-209897D01*
G01X287606Y-203772D02*
X280619D01*
G01X297246Y-209897D02*
Y-192397D01*
X302705D01*
X304451Y-193272D01*
X305543Y-194439D01*
X305980Y-196772D01*
X305543Y-199106D01*
X304233Y-200564D01*
X302705Y-201439D01*
X297246D01*
G01X302705D02*
X305980Y-209897D01*
G01X314310D02*
Y-192397D01*
X318676D01*
X320423Y-193272D01*
X321733Y-194439D01*
X322825Y-196188D01*
X323698Y-198231D01*
X323916Y-201147D01*
X323698Y-204064D01*
X322825Y-206106D01*
X321733Y-207856D01*
X320423Y-209022D01*
X318676Y-209897D01*
X314310D01*
G01X94686Y-164897D02*
Y-147397D01*
X100363Y-161980D01*
X106040Y-147397D01*
Y-164897D01*
G01X117863D02*
X116553Y-164605D01*
X115243Y-163439D01*
X114369Y-161397D01*
X113933Y-159064D01*
X114369Y-156730D01*
X115243Y-154689D01*
X116553Y-153522D01*
X117863Y-153231D01*
X119173Y-153522D01*
X120483Y-154689D01*
X121356Y-156730D01*
X121575Y-159064D01*
X121356Y-161397D01*
X120483Y-163439D01*
X119173Y-164605D01*
X117863Y-164897D01*
G01X139293Y-147397D02*
Y-164897D01*
G01Y-162273D02*
X138420Y-163731D01*
X137109Y-164605D01*
X135581Y-164897D01*
X133835Y-164314D01*
X132525Y-162856D01*
X131651Y-161106D01*
X131433Y-159064D01*
X131651Y-157022D01*
X132525Y-155272D01*
X133835Y-153814D01*
X135581Y-153231D01*
X137109Y-153522D01*
X138201Y-154106D01*
X139293Y-155272D01*
G01X149588Y-157022D02*
X156575D01*
X155920Y-154980D01*
X154828Y-153814D01*
X153300Y-153231D01*
X151771Y-153522D01*
X150461Y-154397D01*
X149588Y-156439D01*
X149151Y-158189D01*
Y-159939D01*
X149588Y-161689D01*
X150680Y-163439D01*
X151990Y-164605D01*
X153518Y-164897D01*
X155046Y-164314D01*
X156575Y-162564D01*
G01X170363Y-164897D02*
Y-147397D01*
G01X376163Y-209897D02*
Y-192397D01*
X373543Y-195897D01*
G01Y-209897D02*
X378783D01*
G01X389515Y-195314D02*
X390825Y-193564D01*
X392353Y-192689D01*
X394100Y-192397D01*
X396283Y-192980D01*
X397811Y-194439D01*
X398248Y-196188D01*
X398030Y-197939D01*
X397156Y-199397D01*
X392790Y-202314D01*
X390825Y-204355D01*
X389515Y-207273D01*
X389078Y-209897D01*
X398248D01*
G01X413783D02*
Y-192397D01*
X405704Y-204939D01*
X416622D01*
G01X423860Y-206397D02*
X425169Y-208439D01*
X426916Y-209605D01*
X428881Y-209897D01*
X430628Y-209605D01*
X432375Y-208147D01*
X433466Y-206397D01*
X433685Y-204647D01*
X433248Y-202606D01*
X431720Y-201147D01*
X430191Y-200564D01*
X428226D01*
G01X430191D02*
X431501Y-199689D01*
X432593Y-198231D01*
X433030Y-196481D01*
X432593Y-194730D01*
X431501Y-193272D01*
X429536Y-192397D01*
X427571Y-192689D01*
X425606Y-193856D01*
G01X442015Y-195314D02*
X443325Y-193564D01*
X444853Y-192689D01*
X446600Y-192397D01*
X448783Y-192980D01*
X450311Y-194439D01*
X450748Y-196188D01*
X450530Y-197939D01*
X449656Y-199397D01*
X445290Y-202314D01*
X443325Y-204355D01*
X442015Y-207273D01*
X441578Y-209897D01*
X450748D01*
G01X363046Y-164897D02*
Y-147397D01*
X368286D01*
X370033Y-148272D01*
X371343Y-150314D01*
X371780Y-152647D01*
X371343Y-154980D01*
X370251Y-156730D01*
X368286Y-157606D01*
X363046D01*
G01X389716Y-148856D02*
X388406Y-147980D01*
X386878Y-147397D01*
X385131D01*
X383166Y-148272D01*
X381638Y-149730D01*
X380546Y-151481D01*
X379673Y-154397D01*
X379454Y-157022D01*
X379891Y-159647D01*
X380546Y-161397D01*
X381856Y-163147D01*
X383385Y-164314D01*
X384913Y-164897D01*
X386441D01*
X387970Y-164314D01*
X389280Y-163439D01*
X390372Y-162273D01*
G01X404159Y-155564D02*
X405033Y-154689D01*
X405688Y-153231D01*
X406125Y-151188D01*
X405688Y-149439D01*
X404815Y-148272D01*
X403286Y-147397D01*
X397391D01*
Y-164897D01*
X404596D01*
X406125Y-163731D01*
X406998Y-161980D01*
X407435Y-159939D01*
X406998Y-157897D01*
X405688Y-156147D01*
X404159Y-155564D01*
X397391D01*
G01X413363Y-170730D02*
X426463D01*
G01X432391Y-164897D02*
Y-147397D01*
X442435Y-164897D01*
Y-147397D01*
G01X454913Y-164897D02*
X453166Y-164605D01*
X451638Y-163439D01*
X450328Y-161689D01*
X449454Y-159647D01*
X449018Y-157314D01*
Y-154980D01*
X449454Y-152647D01*
X450328Y-150605D01*
X451638Y-148856D01*
X453166Y-147689D01*
X454913Y-147397D01*
X456659Y-147689D01*
X458188Y-148856D01*
X459498Y-150605D01*
X460372Y-152647D01*
X460808Y-154980D01*
Y-157314D01*
X460372Y-159647D01*
X459498Y-161689D01*
X458188Y-163439D01*
X456659Y-164605D01*
X454913Y-164897D01*
G01X505754Y-147397D02*
X511213Y-164897D01*
X516672Y-147397D01*
G01X533080Y-164897D02*
X524346D01*
Y-147397D01*
X533080D01*
G01X529586Y-155855D02*
X524346D01*
G01X541846Y-164897D02*
Y-147397D01*
X547305D01*
X549051Y-148272D01*
X550143Y-149439D01*
X550580Y-151772D01*
X550143Y-154106D01*
X548833Y-155564D01*
X547305Y-156439D01*
X541846D01*
G01X547305D02*
X550580Y-164897D01*
G01X563713Y-165480D02*
X563276Y-165189D01*
Y-164605D01*
X563713Y-164314D01*
X564150Y-164605D01*
Y-165189D01*
X563713Y-165480D01*
G01X537463Y-209897D02*
Y-192397D01*
X534843Y-195897D01*
G01Y-209897D02*
X540083D01*
G01X630546Y-147397D02*
Y-164897D01*
X639280D01*
G01X656343D02*
Y-153231D01*
G01Y-155272D02*
X655470Y-154106D01*
X654159Y-153522D01*
X652631Y-153231D01*
X651103Y-153814D01*
X649793Y-154980D01*
X648919Y-156730D01*
X648483Y-159064D01*
X648919Y-161397D01*
X649793Y-163147D01*
X651103Y-164314D01*
X652631Y-164897D01*
X654159Y-164605D01*
X655470Y-163731D01*
X656343Y-162564D01*
G01X665328Y-170147D02*
X666638Y-170730D01*
X668385Y-170147D01*
X669476Y-168981D01*
X670350Y-167522D01*
X671659Y-162856D01*
X674498Y-153231D01*
G01X667511D02*
X671659Y-162856D01*
G01X684138Y-157022D02*
X691125D01*
X690470Y-154980D01*
X689378Y-153814D01*
X687850Y-153231D01*
X686321Y-153522D01*
X685011Y-154397D01*
X684138Y-156439D01*
X683701Y-158189D01*
Y-159939D01*
X684138Y-161689D01*
X685230Y-163439D01*
X686540Y-164605D01*
X688068Y-164897D01*
X689596Y-164314D01*
X691125Y-162564D01*
G01X701856Y-164897D02*
Y-153231D01*
G01Y-155564D02*
X702948Y-154397D01*
X704040Y-153522D01*
X705568Y-153231D01*
X706659Y-153522D01*
X707970Y-154397D01*
G01X719138Y-162856D02*
X720230Y-164022D01*
X721758Y-164897D01*
X723068D01*
X724378Y-164314D01*
X725251Y-163439D01*
X725688Y-162273D01*
X725470Y-160522D01*
X724596Y-159647D01*
X720666Y-157897D01*
X719793Y-155855D01*
X720230Y-154397D01*
X721103Y-153522D01*
X722413Y-153231D01*
X723723Y-153522D01*
X725033Y-154397D01*
G01X639296Y-192397D02*
Y-209897D01*
X648030D01*
G01X657015Y-195314D02*
X658325Y-193564D01*
X659853Y-192689D01*
X661600Y-192397D01*
X663783Y-192980D01*
X665311Y-194439D01*
X665748Y-196188D01*
X665530Y-197939D01*
X664656Y-199397D01*
X660290Y-202314D01*
X658325Y-204355D01*
X657015Y-207273D01*
X656578Y-209897D01*
X665748D01*
G01X679973Y-201147D02*
X684340D01*
Y-206397D01*
X683030Y-208147D01*
X681501Y-209314D01*
X679318Y-209897D01*
X677135Y-209314D01*
X675606Y-208147D01*
X674296Y-206397D01*
X673423Y-204355D01*
X672986Y-202022D01*
Y-199980D01*
X673423Y-198231D01*
X674296Y-196188D01*
X675606Y-194439D01*
X676916Y-193272D01*
X678663Y-192397D01*
X680191D01*
X681938Y-192980D01*
X683248Y-194147D01*
G01X691141Y-209897D02*
Y-192397D01*
X701185Y-209897D01*
Y-192397D01*
G01X708860Y-209897D02*
Y-192397D01*
X713226D01*
X714973Y-193272D01*
X716283Y-194439D01*
X717375Y-196188D01*
X718248Y-198231D01*
X718466Y-201147D01*
X718248Y-204064D01*
X717375Y-206106D01*
X716283Y-207856D01*
X714973Y-209022D01*
X713226Y-209897D01*
X708860D01*
G01X781410Y-164897D02*
Y-147397D01*
X785776D01*
X787523Y-148272D01*
X788833Y-149439D01*
X789925Y-151188D01*
X790798Y-153231D01*
X791016Y-156147D01*
X790798Y-159064D01*
X789925Y-161106D01*
X788833Y-162856D01*
X787523Y-164022D01*
X785776Y-164897D01*
X781410D01*
G01X800438Y-157022D02*
X807425D01*
X806770Y-154980D01*
X805678Y-153814D01*
X804150Y-153231D01*
X802621Y-153522D01*
X801311Y-154397D01*
X800438Y-156439D01*
X800001Y-158189D01*
Y-159939D01*
X800438Y-161689D01*
X801530Y-163439D01*
X802840Y-164605D01*
X804368Y-164897D01*
X805896Y-164314D01*
X807425Y-162564D01*
G01X817938Y-162856D02*
X819030Y-164022D01*
X820558Y-164897D01*
X821868D01*
X823178Y-164314D01*
X824051Y-163439D01*
X824488Y-162273D01*
X824270Y-160522D01*
X823396Y-159647D01*
X819466Y-157897D01*
X818593Y-155855D01*
X819030Y-154397D01*
X819903Y-153522D01*
X821213Y-153231D01*
X822523Y-153522D01*
X823833Y-154397D01*
G01X838713Y-153231D02*
Y-164897D01*
G01Y-148564D02*
X838276Y-148272D01*
Y-147689D01*
X838713Y-147397D01*
X839150Y-147689D01*
Y-148272D01*
X838713Y-148564D01*
G01X853156Y-169272D02*
X854685Y-170439D01*
X856431Y-170730D01*
X857959Y-170439D01*
X859270Y-168981D01*
X860143Y-166939D01*
Y-153231D01*
G01Y-155564D02*
X859270Y-154397D01*
X857959Y-153522D01*
X856431Y-153231D01*
X854685Y-153814D01*
X853593Y-154980D01*
X852719Y-157022D01*
X852283Y-159064D01*
X852501Y-160814D01*
X853375Y-162856D01*
X854685Y-164314D01*
X856431Y-164897D01*
X857741Y-164605D01*
X859270Y-163439D01*
X860143Y-162273D01*
G01X870001Y-164897D02*
Y-153231D01*
G01Y-156147D02*
X870875Y-154689D01*
X872185Y-153522D01*
X873931Y-153231D01*
X875459Y-153522D01*
X876770Y-154689D01*
X877425Y-156730D01*
Y-164897D01*
G01X887938Y-157022D02*
X894925D01*
X894270Y-154980D01*
X893178Y-153814D01*
X891650Y-153231D01*
X890121Y-153522D01*
X888811Y-154397D01*
X887938Y-156439D01*
X887501Y-158189D01*
Y-159939D01*
X887938Y-161689D01*
X889030Y-163439D01*
X890340Y-164605D01*
X891868Y-164897D01*
X893396Y-164314D01*
X894925Y-162564D01*
G01X905656Y-164897D02*
Y-153231D01*
G01Y-155564D02*
X906748Y-154397D01*
X907840Y-153522D01*
X909368Y-153231D01*
X910459Y-153522D01*
X911770Y-154397D01*
G01X825596Y-209897D02*
Y-192397D01*
X831055D01*
X832801Y-193272D01*
X833893Y-194439D01*
X834330Y-196772D01*
X833893Y-199106D01*
X832583Y-200564D01*
X831055Y-201439D01*
X825596D01*
G01X831055D02*
X834330Y-209897D01*
G01X847463D02*
X846153Y-209605D01*
X844843Y-208439D01*
X843969Y-206397D01*
X843533Y-204064D01*
X843969Y-201730D01*
X844843Y-199689D01*
X846153Y-198522D01*
X847463Y-198231D01*
X848773Y-198522D01*
X850083Y-199689D01*
X850956Y-201730D01*
X851175Y-204064D01*
X850956Y-206397D01*
X850083Y-208439D01*
X848773Y-209605D01*
X847463Y-209897D01*
G01X861033D02*
Y-192397D01*
G01Y-201147D02*
X862125Y-199397D01*
X863435Y-198522D01*
X864745Y-198231D01*
X866709Y-198814D01*
X868020Y-199980D01*
X868893Y-202022D01*
Y-204355D01*
X868456Y-206689D01*
X867583Y-208439D01*
X866055Y-209605D01*
X864745Y-209897D01*
X863435Y-209605D01*
X862125Y-208731D01*
X861033Y-207273D01*
G01X952413Y-209897D02*
Y-192397D01*
X949793Y-195897D01*
G01Y-209897D02*
X955033D01*
G01X969913Y-192397D02*
X968166Y-192980D01*
X966856Y-194439D01*
X965983Y-196188D01*
X965328Y-198522D01*
X965110Y-201147D01*
X965328Y-203772D01*
X965983Y-206106D01*
X966856Y-207856D01*
X968166Y-209314D01*
X969913Y-209897D01*
X971659Y-209314D01*
X972970Y-207856D01*
X973843Y-206106D01*
X974498Y-203772D01*
X974716Y-201147D01*
X974498Y-198522D01*
X973843Y-196188D01*
X972970Y-194439D01*
X971659Y-192980D01*
X969913Y-192397D01*
G01X983483Y-210480D02*
X991343Y-192397D01*
G01X1004913Y-209897D02*
Y-192397D01*
X1002293Y-195897D01*
G01Y-209897D02*
X1007533D01*
G01X1018265Y-202606D02*
X1019793Y-200564D01*
X1021103Y-199397D01*
X1022850Y-198814D01*
X1024378Y-199397D01*
X1025470Y-200564D01*
X1026343Y-202314D01*
X1026561Y-204355D01*
X1026343Y-206106D01*
X1025470Y-207856D01*
X1024159Y-209314D01*
X1022631Y-209897D01*
X1020885Y-209314D01*
X1019356Y-207564D01*
X1018483Y-204939D01*
X1018265Y-202022D01*
X1018701Y-198231D01*
X1019356Y-196188D01*
X1020448Y-194147D01*
X1021976Y-192689D01*
X1023505Y-192397D01*
X1025033Y-192980D01*
X1026125Y-194439D01*
G01X1035983Y-210480D02*
X1043843Y-192397D01*
G01X1053265Y-195314D02*
X1054575Y-193564D01*
X1056103Y-192689D01*
X1057850Y-192397D01*
X1060033Y-192980D01*
X1061561Y-194439D01*
X1061998Y-196188D01*
X1061780Y-197939D01*
X1060906Y-199397D01*
X1056540Y-202314D01*
X1054575Y-204355D01*
X1053265Y-207273D01*
X1052828Y-209897D01*
X1061998D01*
G01X1074913Y-192397D02*
X1073166Y-192980D01*
X1071856Y-194439D01*
X1070983Y-196188D01*
X1070328Y-198522D01*
X1070110Y-201147D01*
X1070328Y-203772D01*
X1070983Y-206106D01*
X1071856Y-207856D01*
X1073166Y-209314D01*
X1074913Y-209897D01*
X1076659Y-209314D01*
X1077970Y-207856D01*
X1078843Y-206106D01*
X1079498Y-203772D01*
X1079716Y-201147D01*
X1079498Y-198522D01*
X1078843Y-196188D01*
X1077970Y-194439D01*
X1076659Y-192980D01*
X1074913Y-192397D01*
G01X1092413Y-209897D02*
Y-192397D01*
X1089793Y-195897D01*
G01Y-209897D02*
X1095033D01*
G01X1105765Y-195314D02*
X1107075Y-193564D01*
X1108603Y-192689D01*
X1110350Y-192397D01*
X1112533Y-192980D01*
X1114061Y-194439D01*
X1114498Y-196188D01*
X1114280Y-197939D01*
X1113406Y-199397D01*
X1109040Y-202314D01*
X1107075Y-204355D01*
X1105765Y-207273D01*
X1105328Y-209897D01*
X1114498D01*
G01X1000110Y-164897D02*
Y-147397D01*
X1004476D01*
X1006223Y-148272D01*
X1007533Y-149439D01*
X1008625Y-151188D01*
X1009498Y-153231D01*
X1009716Y-156147D01*
X1009498Y-159064D01*
X1008625Y-161106D01*
X1007533Y-162856D01*
X1006223Y-164022D01*
X1004476Y-164897D01*
X1000110D01*
G01X1026343D02*
Y-153231D01*
G01Y-155272D02*
X1025470Y-154106D01*
X1024159Y-153522D01*
X1022631Y-153231D01*
X1021103Y-153814D01*
X1019793Y-154980D01*
X1018919Y-156730D01*
X1018483Y-159064D01*
X1018919Y-161397D01*
X1019793Y-163147D01*
X1021103Y-164314D01*
X1022631Y-164897D01*
X1024159Y-164605D01*
X1025470Y-163731D01*
X1026343Y-162564D01*
G01X1039913Y-147397D02*
Y-164897D01*
G01X1036856Y-153231D02*
X1042970D01*
G01X1054138Y-157022D02*
X1061125D01*
X1060470Y-154980D01*
X1059378Y-153814D01*
X1057850Y-153231D01*
X1056321Y-153522D01*
X1055011Y-154397D01*
X1054138Y-156439D01*
X1053701Y-158189D01*
Y-159939D01*
X1054138Y-161689D01*
X1055230Y-163439D01*
X1056540Y-164605D01*
X1058068Y-164897D01*
X1059596Y-164314D01*
X1061125Y-162564D01*
M02*
